G04 ================== begin FILE IDENTIFICATION RECORD ==================*
G04 Layout Name:  15968-1a.brd*
G04 Film Name:    L1*
G04 File Format:  Gerber RS274X*
G04 File Origin:  Cadence Allegro 16.5-S058*
G04 Origin Date:  Fri Oct 14 10:23:37 2016*
G04 *
G04 Layer:  VIA CLASS/TOP*
G04 Layer:  PIN/TOP*
G04 Layer:  ETCH/TOP*
G04 Layer:  DRAWING FORMAT/LAYER_PCB_STORY*
G04 Layer:  DRAWING FORMAT/LAYER_L1*
G04 *
G04 Offset:    (0.00 0.00)*
G04 Mirror:    No*
G04 Mode:      Positive*
G04 Rotation:  0*
G04 FullContactRelief:  No*
G04 UndefLineWidth:     6.00*
G04 ================== end FILE IDENTIFICATION RECORD ====================*
%FSLAX35Y35*MOIN*%
%IR0*IPPOS*OFA0.00000B0.00000*MIA0B0*SFA1.00000B1.00000*%
%AMMACRO56*
4,1,40,.013,.017,
-.013,.017,
-.013695,.016939,
-.014368,.016759,
-.015,.016464,
-.015571,.016064,
-.016064,.015571,
-.016464,.015,
-.016759,.014368,
-.016939,.013695,
-.017,.013,
-.017,-.013,
-.016939,-.013695,
-.016759,-.014368,
-.016464,-.015,
-.016064,-.015571,
-.015571,-.016064,
-.015,-.016464,
-.014368,-.016759,
-.013695,-.016939,
-.013,-.017,
.013,-.017,
.013695,-.016939,
.014368,-.016759,
.015,-.016464,
.015571,-.016064,
.016064,-.015571,
.016464,-.015,
.016759,-.014368,
.016939,-.013695,
.017,-.013,
.017,.013,
.016939,.013695,
.016759,.014368,
.016464,.015,
.016064,.015571,
.015571,.016064,
.015,.016464,
.014368,.016759,
.013695,.016939,
.013,.017,
0.0*
%
%ADD56MACRO56*%
%AMMACRO22*
4,1,40,.017,-.013,
.017,.013,
.016939,.013695,
.016759,.014368,
.016464,.015,
.016064,.015571,
.015571,.016064,
.015,.016464,
.014368,.016759,
.013695,.016939,
.013,.017,
-.013,.017,
-.013695,.016939,
-.014368,.016759,
-.015,.016464,
-.015571,.016064,
-.016064,.015571,
-.016464,.015,
-.016759,.014368,
-.016939,.013695,
-.017,.013,
-.017,-.013,
-.016939,-.013695,
-.016759,-.014368,
-.016464,-.015,
-.016064,-.015571,
-.015571,-.016064,
-.015,-.016464,
-.014368,-.016759,
-.013695,-.016939,
-.013,-.017,
.013,-.017,
.013695,-.016939,
.014368,-.016759,
.015,-.016464,
.015571,-.016064,
.016064,-.015571,
.016464,-.015,
.016759,-.014368,
.016939,-.013695,
.017,-.013,
0.0*
%
%ADD22MACRO22*%
%ADD17R,.022X.11*%
%ADD65R,.022X.102*%
%ADD16R,.141X.061*%
%ADD41R,.061X.141*%
%ADD10C,.01*%
%AMMACRO25*
21,1,.065,.05,0.0,0.0,135.*%
%ADD25MACRO25*%
%ADD14C,.02*%
%ADD48C,.04*%
%ADD12C,.022*%
%ADD63C,.024*%
%ADD54C,.042*%
%ADD15C,.028*%
%ADD40R,.07X.07*%
%AMMACRO45*
4,1,40,.007,.011,
-.007,.011,
-.007695,.010939,
-.008368,.010759,
-.009,.010464,
-.009571,.010064,
-.010064,.009571,
-.010464,.009,
-.010759,.008368,
-.010939,.007695,
-.011,.007,
-.011,-.007,
-.010939,-.007695,
-.010759,-.008368,
-.010464,-.009,
-.010064,-.009571,
-.009571,-.010064,
-.009,-.010464,
-.008368,-.010759,
-.007695,-.010939,
-.007,-.011,
.007,-.011,
.007695,-.010939,
.008368,-.010759,
.009,-.010464,
.009571,-.010064,
.010064,-.009571,
.010464,-.009,
.010759,-.008368,
.010939,-.007695,
.011,-.007,
.011,.007,
.010939,.007695,
.010759,.008368,
.010464,.009,
.010064,.009571,
.009571,.010064,
.009,.010464,
.008368,.010759,
.007695,.010939,
.007,.011,
0.0*
%
%ADD45MACRO45*%
%AMMACRO34*
4,1,40,.011,-.007,
.011,.007,
.010939,.007695,
.010759,.008368,
.010464,.009,
.010064,.009571,
.009571,.010064,
.009,.010464,
.008368,.010759,
.007695,.010939,
.007,.011,
-.007,.011,
-.007695,.010939,
-.008368,.010759,
-.009,.010464,
-.009571,.010064,
-.010064,.009571,
-.010464,.009,
-.010759,.008368,
-.010939,.007695,
-.011,.007,
-.011,-.007,
-.010939,-.007695,
-.010759,-.008368,
-.010464,-.009,
-.010064,-.009571,
-.009571,-.010064,
-.009,-.010464,
-.008368,-.010759,
-.007695,-.010939,
-.007,-.011,
.007,-.011,
.007695,-.010939,
.008368,-.010759,
.009,-.010464,
.009571,-.010064,
.010064,-.009571,
.010464,-.009,
.010759,-.008368,
.010939,-.007695,
.011,-.007,
0.0*
%
%ADD34MACRO34*%
%AMMACRO51*
4,1,40,-.012,.008,
-.012,-.008,
-.011939,-.008695,
-.011759,-.009368,
-.011464,-.01,
-.011064,-.010571,
-.010571,-.011064,
-.01,-.011464,
-.009368,-.011759,
-.008695,-.011939,
-.008,-.012,
.008,-.012,
.008695,-.011939,
.009368,-.011759,
.01,-.011464,
.010571,-.011064,
.011064,-.010571,
.011464,-.01,
.011759,-.009368,
.011939,-.008695,
.012,-.008,
.012,.008,
.011939,.008695,
.011759,.009368,
.011464,.01,
.011064,.010571,
.010571,.011064,
.01,.011464,
.009368,.011759,
.008695,.011939,
.008,.012,
-.008,.012,
-.008695,.011939,
-.009368,.011759,
-.01,.011464,
-.010571,.011064,
-.011064,.010571,
-.011464,.01,
-.011759,.009368,
-.011939,.008695,
-.012,.008,
0.0*
%
%ADD51MACRO51*%
%AMMACRO27*
4,1,40,.008,.012,
-.008,.012,
-.008695,.011939,
-.009368,.011759,
-.01,.011464,
-.010571,.011064,
-.011064,.010571,
-.011464,.01,
-.011759,.009368,
-.011939,.008695,
-.012,.008,
-.012,-.008,
-.011939,-.008695,
-.011759,-.009368,
-.011464,-.01,
-.011064,-.010571,
-.010571,-.011064,
-.01,-.011464,
-.009368,-.011759,
-.008695,-.011939,
-.008,-.012,
.008,-.012,
.008695,-.011939,
.009368,-.011759,
.01,-.011464,
.010571,-.011064,
.011064,-.010571,
.011464,-.01,
.011759,-.009368,
.011939,-.008695,
.012,-.008,
.012,.008,
.011939,.008695,
.011759,.009368,
.011464,.01,
.011064,.010571,
.010571,.011064,
.01,.011464,
.009368,.011759,
.008695,.011939,
.008,.012,
0.0*
%
%ADD27MACRO27*%
%AMMACRO66*
4,1,40,-.013,-.017,
.013,-.017,
.013695,-.016939,
.014368,-.016759,
.015,-.016464,
.015571,-.016064,
.016064,-.015571,
.016464,-.015,
.016759,-.014368,
.016939,-.013695,
.017,-.013,
.017,.013,
.016939,.013695,
.016759,.014368,
.016464,.015,
.016064,.015571,
.015571,.016064,
.015,.016464,
.014368,.016759,
.013695,.016939,
.013,.017,
-.013,.017,
-.013695,.016939,
-.014368,.016759,
-.015,.016464,
-.015571,.016064,
-.016064,.015571,
-.016464,.015,
-.016759,.014368,
-.016939,.013695,
-.017,.013,
-.017,-.013,
-.016939,-.013695,
-.016759,-.014368,
-.016464,-.015,
-.016064,-.015571,
-.015571,-.016064,
-.015,-.016464,
-.014368,-.016759,
-.013695,-.016939,
-.013,-.017,
0.0*
%
%ADD66MACRO66*%
%AMMACRO43*
4,1,40,-.017,.013,
-.017,-.013,
-.016939,-.013695,
-.016759,-.014368,
-.016464,-.015,
-.016064,-.015571,
-.015571,-.016064,
-.015,-.016464,
-.014368,-.016759,
-.013695,-.016939,
-.013,-.017,
.013,-.017,
.013695,-.016939,
.014368,-.016759,
.015,-.016464,
.015571,-.016064,
.016064,-.015571,
.016464,-.015,
.016759,-.014368,
.016939,-.013695,
.017,-.013,
.017,.013,
.016939,.013695,
.016759,.014368,
.016464,.015,
.016064,.015571,
.015571,.016064,
.015,.016464,
.014368,.016759,
.013695,.016939,
.013,.017,
-.013,.017,
-.013695,.016939,
-.014368,.016759,
-.015,.016464,
-.015571,.016064,
-.016064,.015571,
-.016464,.015,
-.016759,.014368,
-.016939,.013695,
-.017,.013,
0.0*
%
%ADD43MACRO43*%
%AMMACRO46*
4,1,40,.007,.011,
-.007,.011,
-.007695,.010939,
-.008368,.010759,
-.009,.010464,
-.009571,.010064,
-.010064,.009571,
-.010464,.009,
-.010759,.008368,
-.010939,.007695,
-.011,.007,
-.011,-.007,
-.010939,-.007695,
-.010759,-.008368,
-.010464,-.009,
-.010064,-.009571,
-.009571,-.010064,
-.009,-.010464,
-.008368,-.010759,
-.007695,-.010939,
-.007,-.011,
.007,-.011,
.007695,-.010939,
.008368,-.010759,
.009,-.010464,
.009571,-.010064,
.010064,-.009571,
.010464,-.009,
.010759,-.008368,
.010939,-.007695,
.011,-.007,
.011,.007,
.010939,.007695,
.010759,.008368,
.010464,.009,
.010064,.009571,
.009571,.010064,
.009,.010464,
.008368,.010759,
.007695,.010939,
.007,.011,
0.0*
%
%ADD46MACRO46*%
%AMMACRO35*
4,1,40,.011,-.007,
.011,.007,
.010939,.007695,
.010759,.008368,
.010464,.009,
.010064,.009571,
.009571,.010064,
.009,.010464,
.008368,.010759,
.007695,.010939,
.007,.011,
-.007,.011,
-.007695,.010939,
-.008368,.010759,
-.009,.010464,
-.009571,.010064,
-.010064,.009571,
-.010464,.009,
-.010759,.008368,
-.010939,.007695,
-.011,.007,
-.011,-.007,
-.010939,-.007695,
-.010759,-.008368,
-.010464,-.009,
-.010064,-.009571,
-.009571,-.010064,
-.009,-.010464,
-.008368,-.010759,
-.007695,-.010939,
-.007,-.011,
.007,-.011,
.007695,-.010939,
.008368,-.010759,
.009,-.010464,
.009571,-.010064,
.010064,-.009571,
.010464,-.009,
.010759,-.008368,
.010939,-.007695,
.011,-.007,
0.0*
%
%ADD35MACRO35*%
%AMMACRO50*
4,1,40,-.012,.008,
-.012,-.008,
-.011939,-.008695,
-.011759,-.009368,
-.011464,-.01,
-.011064,-.010571,
-.010571,-.011064,
-.01,-.011464,
-.009368,-.011759,
-.008695,-.011939,
-.008,-.012,
.008,-.012,
.008695,-.011939,
.009368,-.011759,
.01,-.011464,
.010571,-.011064,
.011064,-.010571,
.011464,-.01,
.011759,-.009368,
.011939,-.008695,
.012,-.008,
.012,.008,
.011939,.008695,
.011759,.009368,
.011464,.01,
.011064,.010571,
.010571,.011064,
.01,.011464,
.009368,.011759,
.008695,.011939,
.008,.012,
-.008,.012,
-.008695,.011939,
-.009368,.011759,
-.01,.011464,
-.010571,.011064,
-.011064,.010571,
-.011464,.01,
-.011759,.009368,
-.011939,.008695,
-.012,.008,
0.0*
%
%ADD50MACRO50*%
%AMMACRO26*
4,1,40,.008,.012,
-.008,.012,
-.008695,.011939,
-.009368,.011759,
-.01,.011464,
-.010571,.011064,
-.011064,.010571,
-.011464,.01,
-.011759,.009368,
-.011939,.008695,
-.012,.008,
-.012,-.008,
-.011939,-.008695,
-.011759,-.009368,
-.011464,-.01,
-.011064,-.010571,
-.010571,-.011064,
-.01,-.011464,
-.009368,-.011759,
-.008695,-.011939,
-.008,-.012,
.008,-.012,
.008695,-.011939,
.009368,-.011759,
.01,-.011464,
.010571,-.011064,
.011064,-.010571,
.011464,-.01,
.011759,-.009368,
.011939,-.008695,
.012,-.008,
.012,.008,
.011939,.008695,
.011759,.009368,
.011464,.01,
.011064,.010571,
.010571,.011064,
.01,.011464,
.009368,.011759,
.008695,.011939,
.008,.012,
0.0*
%
%ADD26MACRO26*%
%AMMACRO64*
4,1,40,-.013,-.017,
.013,-.017,
.013695,-.016939,
.014368,-.016759,
.015,-.016464,
.015571,-.016064,
.016064,-.015571,
.016464,-.015,
.016759,-.014368,
.016939,-.013695,
.017,-.013,
.017,.013,
.016939,.013695,
.016759,.014368,
.016464,.015,
.016064,.015571,
.015571,.016064,
.015,.016464,
.014368,.016759,
.013695,.016939,
.013,.017,
-.013,.017,
-.013695,.016939,
-.014368,.016759,
-.015,.016464,
-.015571,.016064,
-.016064,.015571,
-.016464,.015,
-.016759,.014368,
-.016939,.013695,
-.017,.013,
-.017,-.013,
-.016939,-.013695,
-.016759,-.014368,
-.016464,-.015,
-.016064,-.015571,
-.015571,-.016064,
-.015,-.016464,
-.014368,-.016759,
-.013695,-.016939,
-.013,-.017,
0.0*
%
%ADD64MACRO64*%
%AMMACRO44*
4,1,40,-.017,.013,
-.017,-.013,
-.016939,-.013695,
-.016759,-.014368,
-.016464,-.015,
-.016064,-.015571,
-.015571,-.016064,
-.015,-.016464,
-.014368,-.016759,
-.013695,-.016939,
-.013,-.017,
.013,-.017,
.013695,-.016939,
.014368,-.016759,
.015,-.016464,
.015571,-.016064,
.016064,-.015571,
.016464,-.015,
.016759,-.014368,
.016939,-.013695,
.017,-.013,
.017,.013,
.016939,.013695,
.016759,.014368,
.016464,.015,
.016064,.015571,
.015571,.016064,
.015,.016464,
.014368,.016759,
.013695,.016939,
.013,.017,
-.013,.017,
-.013695,.016939,
-.014368,.016759,
-.015,.016464,
-.015571,.016064,
-.016064,.015571,
-.016464,.015,
-.016759,.014368,
-.016939,.013695,
-.017,.013,
0.0*
%
%ADD44MACRO44*%
%ADD71C,.101*%
%ADD61R,.012X.052*%
%ADD60R,.052X.012*%
%ADD57R,.06X.014*%
%ADD49R,.016X.04*%
%ADD47R,.014X.06*%
%ADD39R,.036X.012*%
%ADD38R,.012X.036*%
%ADD69R,.012X.036*%
%ADD68R,.036X.012*%
%ADD59R,.046X.012*%
%ADD58R,.012X.046*%
%ADD42R,.05X.065*%
%ADD67R,.055X.042*%
%ADD20R,.065X.05*%
%ADD11R,.045X.055*%
%ADD70R,.055X.045*%
%ADD53R,.016X.048*%
%ADD62R,.15X.15*%
%ADD13C,.394*%
%AMMACRO52*
4,1,40,.024,.012,
.024,-.012,
.023878,-.013389,
.023518,-.014736,
.022928,-.016,
.022128,-.017142,
.021142,-.018128,
.02,-.018928,
.018736,-.019518,
.017389,-.019878,
.016,-.02,
-.016,-.02,
-.017389,-.019878,
-.018736,-.019518,
-.02,-.018928,
-.021142,-.018128,
-.022128,-.017142,
-.022928,-.016,
-.023518,-.014736,
-.023878,-.013389,
-.024,-.012,
-.024,.012,
-.023878,.013389,
-.023518,.014736,
-.022928,.016,
-.022128,.017142,
-.021142,.018128,
-.02,.018928,
-.018736,.019518,
-.017389,.019878,
-.016,.02,
.016,.02,
.017389,.019878,
.018736,.019518,
.02,.018928,
.021142,.018128,
.022128,.017142,
.022928,.016,
.023518,.014736,
.023878,.013389,
.024,.012,
0.0*
%
%ADD52MACRO52*%
%AMMACRO36*
4,1,40,-.007,-.011,
.007,-.011,
.007695,-.010939,
.008368,-.010759,
.009,-.010464,
.009571,-.010064,
.010064,-.009571,
.010464,-.009,
.010759,-.008368,
.010939,-.007695,
.011,-.007,
.011,.007,
.010939,.007695,
.010759,.008368,
.010464,.009,
.010064,.009571,
.009571,.010064,
.009,.010464,
.008368,.010759,
.007695,.010939,
.007,.011,
-.007,.011,
-.007695,.010939,
-.008368,.010759,
-.009,.010464,
-.009571,.010064,
-.010064,.009571,
-.010464,.009,
-.010759,.008368,
-.010939,.007695,
-.011,.007,
-.011,-.007,
-.010939,-.007695,
-.010759,-.008368,
-.010464,-.009,
-.010064,-.009571,
-.009571,-.010064,
-.009,-.010464,
-.008368,-.010759,
-.007695,-.010939,
-.007,-.011,
0.0*
%
%ADD36MACRO36*%
%AMMACRO33*
4,1,40,.012,-.008,
.012,.008,
.011939,.008695,
.011759,.009368,
.011464,.01,
.011064,.010571,
.010571,.011064,
.01,.011464,
.009368,.011759,
.008695,.011939,
.008,.012,
-.008,.012,
-.008695,.011939,
-.009368,.011759,
-.01,.011464,
-.010571,.011064,
-.011064,.010571,
-.011464,.01,
-.011759,.009368,
-.011939,.008695,
-.012,.008,
-.012,-.008,
-.011939,-.008695,
-.011759,-.009368,
-.011464,-.01,
-.011064,-.010571,
-.010571,-.011064,
-.01,-.011464,
-.009368,-.011759,
-.008695,-.011939,
-.008,-.012,
.008,-.012,
.008695,-.011939,
.009368,-.011759,
.01,-.011464,
.010571,-.011064,
.011064,-.010571,
.011464,-.01,
.011759,-.009368,
.011939,-.008695,
.012,-.008,
0.0*
%
%ADD33MACRO33*%
%AMMACRO31*
4,1,40,-.008,-.012,
.008,-.012,
.008695,-.011939,
.009368,-.011759,
.01,-.011464,
.010571,-.011064,
.011064,-.010571,
.011464,-.01,
.011759,-.009368,
.011939,-.008695,
.012,-.008,
.012,.008,
.011939,.008695,
.011759,.009368,
.011464,.01,
.011064,.010571,
.010571,.011064,
.01,.011464,
.009368,.011759,
.008695,.011939,
.008,.012,
-.008,.012,
-.008695,.011939,
-.009368,.011759,
-.01,.011464,
-.010571,.011064,
-.011064,.010571,
-.011464,.01,
-.011759,.009368,
-.011939,.008695,
-.012,.008,
-.012,-.008,
-.011939,-.008695,
-.011759,-.009368,
-.011464,-.01,
-.011064,-.010571,
-.010571,-.011064,
-.01,-.011464,
-.009368,-.011759,
-.008695,-.011939,
-.008,-.012,
0.0*
%
%ADD31MACRO31*%
%AMMACRO29*
4,1,44,-.01414,-.00283,
-.00283,-.01414,
-.002296,-.014589,
-.001693,-.014938,
-.001038,-.015177,
-.000351,-.015298,
.000346,-.015299,
.001033,-.015178,
.001688,-.01494,
.002292,-.014592,
.002827,-.014144,
.00283,-.01414,
.01414,-.00283,
.014589,-.002296,
.014938,-.001693,
.015177,-.001038,
.015298,-.000351,
.015299,.000346,
.015178,.001033,
.01494,.001688,
.014592,.002292,
.014144,.002827,
.01414,.00283,
.00283,.01414,
.002296,.014589,
.001693,.014938,
.001038,.015177,
.000351,.015298,
-.000346,.015299,
-.001033,.015178,
-.001688,.01494,
-.002292,.014592,
-.002827,.014144,
-.00283,.01414,
-.01414,.00283,
-.014589,.002296,
-.014938,.001693,
-.015177,.001038,
-.015298,.000351,
-.015299,-.000346,
-.015178,-.001033,
-.01494,-.001688,
-.014592,-.002292,
-.014144,-.002827,
-.01414,-.00283,
0.0*
%
%ADD29MACRO29*%
%AMMACRO23*
4,1,40,-.01273,-.00283,
-.00283,-.01273,
-.002294,-.013176,
-.00169,-.013525,
-.001035,-.013763,
-.000348,-.013884,
.000349,-.013884,
.001036,-.013763,
.001691,-.013525,
.002295,-.013176,
.00283,-.01273,
.01273,-.00283,
.013176,-.002294,
.013525,-.00169,
.013763,-.001035,
.013884,-.000348,
.013884,.000349,
.013763,.001036,
.013525,.001691,
.013176,.002295,
.01273,.00283,
.00283,.01273,
.002294,.013176,
.00169,.013525,
.001035,.013763,
.000348,.013884,
-.000349,.013884,
-.001036,.013763,
-.001691,.013525,
-.002295,.013176,
-.00283,.01273,
-.01273,.00283,
-.013176,.002294,
-.013525,.00169,
-.013763,.001035,
-.013884,.000348,
-.013884,-.000349,
-.013763,-.001036,
-.013525,-.001691,
-.013176,-.002295,
-.01273,-.00283,
0.0*
%
%ADD23MACRO23*%
%AMMACRO18*
4,1,40,-.011,.007,
-.011,-.007,
-.010939,-.007695,
-.010759,-.008368,
-.010464,-.009,
-.010064,-.009571,
-.009571,-.010064,
-.009,-.010464,
-.008368,-.010759,
-.007695,-.010939,
-.007,-.011,
.007,-.011,
.007695,-.010939,
.008368,-.010759,
.009,-.010464,
.009571,-.010064,
.010064,-.009571,
.010464,-.009,
.010759,-.008368,
.010939,-.007695,
.011,-.007,
.011,.007,
.010939,.007695,
.010759,.008368,
.010464,.009,
.010064,.009571,
.009571,.010064,
.009,.010464,
.008368,.010759,
.007695,.010939,
.007,.011,
-.007,.011,
-.007695,.010939,
-.008368,.010759,
-.009,.010464,
-.009571,.010064,
-.010064,.009571,
-.010464,.009,
-.010759,.008368,
-.010939,.007695,
-.011,.007,
0.0*
%
%ADD18MACRO18*%
%AMMACRO55*
4,1,40,.013,.017,
-.013,.017,
-.013695,.016939,
-.014368,.016759,
-.015,.016464,
-.015571,.016064,
-.016064,.015571,
-.016464,.015,
-.016759,.014368,
-.016939,.013695,
-.017,.013,
-.017,-.013,
-.016939,-.013695,
-.016759,-.014368,
-.016464,-.015,
-.016064,-.015571,
-.015571,-.016064,
-.015,-.016464,
-.014368,-.016759,
-.013695,-.016939,
-.013,-.017,
.013,-.017,
.013695,-.016939,
.014368,-.016759,
.015,-.016464,
.015571,-.016064,
.016064,-.015571,
.016464,-.015,
.016759,-.014368,
.016939,-.013695,
.017,-.013,
.017,.013,
.016939,.013695,
.016759,.014368,
.016464,.015,
.016064,.015571,
.015571,.016064,
.015,.016464,
.014368,.016759,
.013695,.016939,
.013,.017,
0.0*
%
%ADD55MACRO55*%
%AMMACRO21*
4,1,40,.017,-.013,
.017,.013,
.016939,.013695,
.016759,.014368,
.016464,.015,
.016064,.015571,
.015571,.016064,
.015,.016464,
.014368,.016759,
.013695,.016939,
.013,.017,
-.013,.017,
-.013695,.016939,
-.014368,.016759,
-.015,.016464,
-.015571,.016064,
-.016064,.015571,
-.016464,.015,
-.016759,.014368,
-.016939,.013695,
-.017,.013,
-.017,-.013,
-.016939,-.013695,
-.016759,-.014368,
-.016464,-.015,
-.016064,-.015571,
-.015571,-.016064,
-.015,-.016464,
-.014368,-.016759,
-.013695,-.016939,
-.013,-.017,
.013,-.017,
.013695,-.016939,
.014368,-.016759,
.015,-.016464,
.015571,-.016064,
.016064,-.015571,
.016464,-.015,
.016759,-.014368,
.016939,-.013695,
.017,-.013,
0.0*
%
%ADD21MACRO21*%
%AMMACRO37*
4,1,40,-.007,-.011,
.007,-.011,
.007695,-.010939,
.008368,-.010759,
.009,-.010464,
.009571,-.010064,
.010064,-.009571,
.010464,-.009,
.010759,-.008368,
.010939,-.007695,
.011,-.007,
.011,.007,
.010939,.007695,
.010759,.008368,
.010464,.009,
.010064,.009571,
.009571,.010064,
.009,.010464,
.008368,.010759,
.007695,.010939,
.007,.011,
-.007,.011,
-.007695,.010939,
-.008368,.010759,
-.009,.010464,
-.009571,.010064,
-.010064,.009571,
-.010464,.009,
-.010759,.008368,
-.010939,.007695,
-.011,.007,
-.011,-.007,
-.010939,-.007695,
-.010759,-.008368,
-.010464,-.009,
-.010064,-.009571,
-.009571,-.010064,
-.009,-.010464,
-.008368,-.010759,
-.007695,-.010939,
-.007,-.011,
0.0*
%
%ADD37MACRO37*%
%AMMACRO32*
4,1,40,.012,-.008,
.012,.008,
.011939,.008695,
.011759,.009368,
.011464,.01,
.011064,.010571,
.010571,.011064,
.01,.011464,
.009368,.011759,
.008695,.011939,
.008,.012,
-.008,.012,
-.008695,.011939,
-.009368,.011759,
-.01,.011464,
-.010571,.011064,
-.011064,.010571,
-.011464,.01,
-.011759,.009368,
-.011939,.008695,
-.012,.008,
-.012,-.008,
-.011939,-.008695,
-.011759,-.009368,
-.011464,-.01,
-.011064,-.010571,
-.010571,-.011064,
-.01,-.011464,
-.009368,-.011759,
-.008695,-.011939,
-.008,-.012,
.008,-.012,
.008695,-.011939,
.009368,-.011759,
.01,-.011464,
.010571,-.011064,
.011064,-.010571,
.011464,-.01,
.011759,-.009368,
.011939,-.008695,
.012,-.008,
0.0*
%
%ADD32MACRO32*%
%AMMACRO30*
4,1,40,-.008,-.012,
.008,-.012,
.008695,-.011939,
.009368,-.011759,
.01,-.011464,
.010571,-.011064,
.011064,-.010571,
.011464,-.01,
.011759,-.009368,
.011939,-.008695,
.012,-.008,
.012,.008,
.011939,.008695,
.011759,.009368,
.011464,.01,
.011064,.010571,
.010571,.011064,
.01,.011464,
.009368,.011759,
.008695,.011939,
.008,.012,
-.008,.012,
-.008695,.011939,
-.009368,.011759,
-.01,.011464,
-.010571,.011064,
-.011064,.010571,
-.011464,.01,
-.011759,.009368,
-.011939,.008695,
-.012,.008,
-.012,-.008,
-.011939,-.008695,
-.011759,-.009368,
-.011464,-.01,
-.011064,-.010571,
-.010571,-.011064,
-.01,-.011464,
-.009368,-.011759,
-.008695,-.011939,
-.008,-.012,
0.0*
%
%ADD30MACRO30*%
%AMMACRO28*
4,1,44,-.01414,-.00283,
-.00283,-.01414,
-.002296,-.014589,
-.001693,-.014938,
-.001038,-.015177,
-.000351,-.015298,
.000346,-.015299,
.001033,-.015178,
.001688,-.01494,
.002292,-.014592,
.002827,-.014144,
.00283,-.01414,
.01414,-.00283,
.014589,-.002296,
.014938,-.001693,
.015177,-.001038,
.015298,-.000351,
.015299,.000346,
.015178,.001033,
.01494,.001688,
.014592,.002292,
.014144,.002827,
.01414,.00283,
.00283,.01414,
.002296,.014589,
.001693,.014938,
.001038,.015177,
.000351,.015298,
-.000346,.015299,
-.001033,.015178,
-.001688,.01494,
-.002292,.014592,
-.002827,.014144,
-.00283,.01414,
-.01414,.00283,
-.014589,.002296,
-.014938,.001693,
-.015177,.001038,
-.015298,.000351,
-.015299,-.000346,
-.015178,-.001033,
-.01494,-.001688,
-.014592,-.002292,
-.014144,-.002827,
-.01414,-.00283,
0.0*
%
%ADD28MACRO28*%
%AMMACRO24*
4,1,40,-.01273,-.00283,
-.00283,-.01273,
-.002294,-.013176,
-.00169,-.013525,
-.001035,-.013763,
-.000348,-.013884,
.000349,-.013884,
.001036,-.013763,
.001691,-.013525,
.002295,-.013176,
.00283,-.01273,
.01273,-.00283,
.013176,-.002294,
.013525,-.00169,
.013763,-.001035,
.013884,-.000348,
.013884,.000349,
.013763,.001036,
.013525,.001691,
.013176,.002295,
.01273,.00283,
.00283,.01273,
.002294,.013176,
.00169,.013525,
.001035,.013763,
.000348,.013884,
-.000349,.013884,
-.001036,.013763,
-.001691,.013525,
-.002295,.013176,
-.00283,.01273,
-.01273,.00283,
-.013176,.002294,
-.013525,.00169,
-.013763,.001035,
-.013884,.000348,
-.013884,-.000349,
-.013763,-.001036,
-.013525,-.001691,
-.013176,-.002295,
-.01273,-.00283,
0.0*
%
%ADD24MACRO24*%
%AMMACRO19*
4,1,40,-.011,.007,
-.011,-.007,
-.010939,-.007695,
-.010759,-.008368,
-.010464,-.009,
-.010064,-.009571,
-.009571,-.010064,
-.009,-.010464,
-.008368,-.010759,
-.007695,-.010939,
-.007,-.011,
.007,-.011,
.007695,-.010939,
.008368,-.010759,
.009,-.010464,
.009571,-.010064,
.010064,-.009571,
.010464,-.009,
.010759,-.008368,
.010939,-.007695,
.011,-.007,
.011,.007,
.010939,.007695,
.010759,.008368,
.010464,.009,
.010064,.009571,
.009571,.010064,
.009,.010464,
.008368,.010759,
.007695,.010939,
.007,.011,
-.007,.011,
-.007695,.010939,
-.008368,.010759,
-.009,.010464,
-.009571,.010064,
-.010064,.009571,
-.010464,.009,
-.010759,.008368,
-.010939,.007695,
-.011,.007,
0.0*
%
%ADD19MACRO19*%
%ADD72C,.012*%
%ADD73C,.014*%
%ADD74C,.016*%
%ADD75C,.018*%
%ADD76C,.004*%
%ADD77C,.005*%
%ADD78C,.006*%
%ADD79C,.008*%
%ADD80C,.0045*%
%ADD84R,.008X.02*%
%ADD85C,.09204*%
%ADD83C,.06604*%
%ADD82C,.11004*%
%ADD86C,.12504*%
%ADD81R,.008X.008*%
G75*
%LPD*%
G75*
G36*
G01X75954Y-69408D02*
Y-854D01*
X72100Y3000D01*
X15600D01*
X15525Y3075D01*
X11375D01*
X3150Y11300D01*
Y71150D01*
X35000Y103000D01*
X38300D01*
X43600Y97700D01*
Y96900D01*
X42400Y95700D01*
Y93300D01*
X30900Y81800D01*
Y73100D01*
X30200Y72400D01*
X23400D01*
X18000Y67000D01*
Y22500D01*
X24500Y16000D01*
X78500D01*
X93900Y600D01*
Y-69408D01*
X91700D01*
Y-58700D01*
X91400Y-58400D01*
X90800D01*
X90700Y-58500D01*
Y-69408D01*
X88500D01*
Y-58600D01*
X88400Y-58500D01*
X87700D01*
X87600Y-58600D01*
Y-69408D01*
X85400D01*
Y-58900D01*
X85300Y-58800D01*
X84500D01*
X84400Y-58900D01*
Y-69408D01*
X82200D01*
Y-58800D01*
X82100Y-58700D01*
X81400D01*
X81200Y-58900D01*
Y-69408D01*
X79100D01*
Y-58800D01*
X79000Y-58700D01*
X78200D01*
X78000Y-58900D01*
Y-69408D01*
X75954D01*
G37*
G36*
G01X3001Y159900D02*
Y238051D01*
G02X3937Y238987I936J0D01*
G01X107813D01*
X109500Y237300D01*
Y227300D01*
X107700Y225500D01*
X107121D01*
X107107Y225502D01*
G03X106878Y225518I-226J-1585D01*
G01X105478D01*
G03X105249Y225502I-3J-1601D01*
G01X105235Y225500D01*
X104000D01*
X102300Y227200D01*
X44733D01*
G02X44418Y227846I0J400D01*
G03X37495Y227474I-3624J2836D01*
G01X37633Y227333D01*
X32300Y222000D01*
Y175400D01*
X16800Y159900D01*
X3001D01*
G37*
G36*
G01X38850Y149950D02*
X35850D01*
X25950Y159850D01*
X26100Y160000D01*
Y162700D01*
X29400Y166000D01*
X33800D01*
X37500Y162300D01*
Y160000D01*
X42500Y155000D01*
Y153600D01*
X38850Y149950D01*
G37*
G36*
G01X129600Y-20200D02*
X104100D01*
X103400Y-19500D01*
Y4300D01*
X106500Y7400D01*
X130600D01*
X132500Y5500D01*
Y-17300D01*
X129600Y-20200D01*
G37*
G36*
G01X107400Y-69400D02*
Y-56900D01*
X105700Y-55200D01*
Y-52100D01*
X104502Y-50902D01*
Y-50719D01*
X102904Y-49121D01*
Y-24796D01*
X104600Y-23100D01*
X112800D01*
X115300Y-25600D01*
Y-33887D01*
G03X115099Y-36667I1600J-1513D01*
G01X115196Y-36804D01*
X113000Y-39000D01*
Y-69100D01*
X112700Y-69400D01*
X110600D01*
X110500Y-69300D01*
Y-58200D01*
X110200Y-57900D01*
X109900D01*
X109600Y-58200D01*
Y-69300D01*
X109500Y-69400D01*
X107400D01*
G37*
G36*
G01X61500Y93100D02*
X60400Y94200D01*
Y104000D01*
X65098Y108698D01*
X102702D01*
X104400Y107000D01*
X109400D01*
X109636Y106764D01*
X109585Y106641D01*
G03X109464Y106030I1480J-611D01*
G01Y104630D01*
G03X109477Y104421I1601J-5D01*
G02X109081Y103969I-396J-52D01*
G01X97331D01*
X96431Y103069D01*
X91822D01*
X91803Y103073D01*
G03X91500Y103102I-303J-1573D01*
G01X89900D01*
G03X89597Y103073I0J-1602D01*
G01X89578Y103069D01*
X85569D01*
X84200Y101700D01*
Y96000D01*
X81300Y93100D01*
X61500D01*
G37*
G36*
G01X78200Y64200D02*
X65800D01*
X65300Y64700D01*
Y76200D01*
X67400Y78300D01*
Y83800D01*
X68200Y84600D01*
X73500D01*
X73550Y84550D01*
X79550D01*
X80500Y83600D01*
Y66500D01*
X78200Y64200D01*
G37*
G36*
G01X88600Y46700D02*
X75500D01*
X74200Y48000D01*
Y56000D01*
X75800Y57600D01*
X87700D01*
X89400Y55900D01*
Y47500D01*
X88600Y46700D01*
G37*
G36*
G01X101800Y26500D02*
X100100Y28200D01*
Y44600D01*
X102500Y47000D01*
X107322D01*
G03X108100Y46798I779J1400D01*
G01X109500D01*
G03X110236Y46978I-2J1602D01*
G01X110279Y47000D01*
X110800D01*
X111900Y45900D01*
Y27000D01*
X111400Y26500D01*
X101800D01*
G37*
G36*
G01X47300Y58800D02*
X46100Y60000D01*
Y69400D01*
X43500Y72000D01*
X42471D01*
G02X42076Y72461I0J400D01*
G03X37724I-2176J339D01*
G02X37329Y72000I-395J-61D01*
G01X34400D01*
X33100Y73300D01*
Y81169D01*
X36731Y84800D01*
X64300D01*
X65400Y83700D01*
Y78600D01*
X63900Y77100D01*
Y65600D01*
X57100Y58800D01*
X47300D01*
G37*
G36*
G01X70450Y24550D02*
X68350D01*
X67100Y25800D01*
Y38800D01*
X72900Y44600D01*
X93600D01*
X95600Y42600D01*
Y29600D01*
X92300Y26300D01*
X72200D01*
X70450Y24550D01*
G37*
G36*
G01X102165Y175286D02*
X102179Y175385D01*
G03X99685Y177879I-2179J315D01*
G01X99586Y177865D01*
X98000Y179451D01*
Y191079D01*
G03Y192921I-2000J921D01*
G01Y199500D01*
X99500Y201000D01*
X105200D01*
X106080Y200120D01*
Y181900D01*
X107380Y180600D01*
X128800D01*
X130000Y179400D01*
Y167600D01*
X126850Y164450D01*
X115550D01*
X111665Y168335D01*
X111679Y168435D01*
G03X109183Y170931I-2179J317D01*
G01X109083Y170917D01*
X108800Y171200D01*
X104000D01*
X102851Y172349D01*
Y174600D01*
X102165Y175286D01*
G37*
G36*
G01X80798Y125202D02*
X80400Y125600D01*
Y130846D01*
X80700Y131146D01*
X91646D01*
X93392Y129400D01*
X99100D01*
X99900Y128600D01*
Y126031D01*
X99071Y125202D01*
X80798D01*
G37*
G36*
G01X112500Y118900D02*
X106052Y112452D01*
X105952Y112468D01*
G03X102748Y110700I-452J-2968D01*
G01X63900D01*
X53900Y100700D01*
X48700D01*
X41600Y107800D01*
Y112300D01*
X56550Y127250D01*
X74550D01*
X78600Y123200D01*
X80488D01*
G03X83112I1312J2700D01*
G01X99900D01*
X109448Y132748D01*
Y147302D01*
G03Y150698I-2948J1698D01*
G01Y153539D01*
G02X110066Y153874I400J0D01*
G03X114050Y154068I1858J2850D01*
G03X119337Y157982I2126J2656D01*
G02X119708Y158530I372J148D01*
G01X123322D01*
G02X123647Y157898I-1J-400D01*
G03X129585Y156583I2691J-1914D01*
G02X130261Y156939I393J73D01*
G01X130923Y156277D01*
X130917Y156187D01*
G03X133352Y152796I3296J-203D01*
G01X133500Y152756D01*
Y150505D01*
G02X132795Y150246I-400J0D01*
G03Y145972I-2517J-2137D01*
G02X133500Y145713I305J-259D01*
G01Y140665D01*
G02X132795Y140406I-400J0D01*
G03Y136132I-2517J-2137D01*
G02X133500Y135873I305J-259D01*
G01Y133622D01*
X133352Y133582D01*
G03X131060Y129412I861J-3188D01*
G01X131096Y129296D01*
X124600Y122800D01*
X121795D01*
X119510Y120515D01*
G03X114417Y118900I-1910J-2815D01*
G01X112500D01*
G37*
G36*
G01X65750Y216417D02*
G03X61772Y216071I-1750J-2917D01*
G03X56604Y214187I-2172J-2071D01*
G01X56593Y214000D01*
X55700D01*
X52650Y210950D01*
Y210313D01*
X51698Y209362D01*
Y200488D01*
X52650Y199537D01*
Y163450D01*
X46900Y157700D01*
X45900D01*
X35400Y168200D01*
Y220600D01*
X39998Y225198D01*
X101471D01*
X102900Y223769D01*
Y221178D01*
X104089Y219989D01*
X111300D01*
X117218Y225908D01*
X119942D01*
G03X121062Y231127I2461J2202D01*
G02X120500Y231492I-162J365D01*
G01Y238115D01*
X121303Y238918D01*
X123639D01*
G02X123931Y238244I0J-400D01*
G03X128745I2407J-2260D01*
G02X129037Y238918I292J274D01*
G01X131514D01*
G02X131806Y238244I0J-400D01*
G03X134712Y232720I2407J-2260D01*
G02X135172Y232324I60J-395D01*
G01Y229540D01*
G03Y226678I2976J-1431D01*
G01Y219700D01*
G03Y216838I2976J-1431D01*
G01Y214054D01*
G02X134712Y213658I-400J-1D01*
G03X133376Y207200I-498J-3264D01*
G02X133558Y206530I-101J-387D01*
G01X130086Y203058D01*
X107442D01*
X106300Y204200D01*
Y204400D01*
X103027Y207673D01*
X103103Y207806D01*
G03X102622Y211422I-2603J1494D01*
G01X100593Y213452D01*
X97248D01*
X96700Y214000D01*
X70869D01*
X70837Y214161D01*
G03X65750Y216417I-3337J-661D01*
G37*
G36*
G01X144200Y-24115D02*
X135708Y-32608D01*
Y-36310D01*
X118498Y-53519D01*
Y-54002D01*
X118157Y-54343D01*
Y-56043D01*
X115900Y-58300D01*
Y-69300D01*
X115800Y-69400D01*
X113800D01*
X113700Y-69300D01*
Y-42100D01*
X121300Y-34500D01*
Y-32600D01*
X136250Y-17650D01*
Y26550D01*
X163193Y53493D01*
X163195Y53495D01*
G03X163305Y53605I-1501J1611D01*
G01X163307Y53607D01*
X164800Y55100D01*
Y92400D01*
X169400Y97000D01*
Y107035D01*
G03X169402Y107100I-1599J82D01*
G01Y108700D01*
G03X169400Y108765I-1601J-17D01*
G01Y111000D01*
X168300Y112100D01*
X162900D01*
X162200Y112800D01*
X158500D01*
X155300Y116000D01*
Y127368D01*
G02X155930Y127695I400J0D01*
G03X160178Y132718I1903J2699D01*
G02X160462Y133400I284J282D01*
G01X164400D01*
X164800Y133000D01*
Y124300D01*
X166993Y122107D01*
X172540Y112222D01*
X173100Y110648D01*
Y106900D01*
X174850Y105150D01*
Y97450D01*
X178400Y93900D01*
Y52900D01*
X144200Y18700D01*
Y-24115D01*
G37*
G36*
G01X146000Y76800D02*
X145450Y77350D01*
Y108650D01*
X147600Y110800D01*
X167000D01*
X167300Y110500D01*
Y110400D01*
X168198Y109502D01*
Y98798D01*
X161500Y92100D01*
Y85400D01*
X158600Y82500D01*
X153300D01*
X152402Y81602D01*
X151457D01*
X146655Y76800D01*
X146000D01*
G37*
G36*
G01X125600Y104946D02*
Y115100D01*
X136500Y126000D01*
Y128012D01*
G03Y132776I-2287J2382D01*
G01Y134784D01*
G02X137035Y135160I400J0D01*
G03Y141378I1113J3109D01*
G02X136500Y141754I-135J376D01*
G01Y144624D01*
G02X137035Y145000I400J0D01*
G03Y151218I1113J3109D01*
G02X136500Y151594I-135J376D01*
G01Y153602D01*
G03X136558Y158309I-2287J2382D01*
G01X136500Y158367D01*
Y158400D01*
X135424Y159476D01*
Y159600D01*
X133200Y161824D01*
Y178100D01*
X133100Y178200D01*
Y179500D01*
X130400Y182200D01*
X107694D01*
X107594Y182300D01*
Y199494D01*
X109000Y200900D01*
X132346D01*
X139081Y207635D01*
Y207766D01*
G02X139763Y208050I400J0D01*
G03Y212738I2325J2344D01*
G02X139081Y213022I-282J284D01*
G01Y215098D01*
X139216Y215145D01*
G03Y221393I-1068J3124D01*
G01X139081Y221440D01*
Y224938D01*
X139216Y224985D01*
G03Y231233I-1068J3124D01*
G01X139081Y231280D01*
Y233356D01*
G02X139763Y233640I400J0D01*
G03X144899Y237716I2324J2345D01*
G02X145240Y238326I341J210D01*
G01X146811D01*
G02X147152Y237716I0J-400D01*
G03X152788Y237693I2811J-1732D01*
G02X153131Y238300I342J207D01*
G01X154665D01*
G02X155008Y237693I1J-400D01*
G03X161111Y236384I2825J-1709D01*
G01X161099Y236480D01*
X161309Y236691D01*
X161750Y236250D01*
Y231411D01*
G03Y224807I23J-3302D01*
G01Y222600D01*
X160440Y221290D01*
G03X158752Y219602I1333J-3021D01*
G01X157819Y218669D01*
G02X157143Y218878I-283J283D01*
G03X153658Y214976I-3245J-609D01*
G01X153732Y214970D01*
X153926Y214776D01*
X153700Y214550D01*
Y178100D01*
X161794Y170006D01*
Y151411D01*
G03Y144807I-21J-3302D01*
G01Y141571D01*
G03X159471Y135902I-21J-3302D01*
G02X159475Y135332I-279J-287D01*
G01X159095Y134952D01*
X155752D01*
X153700Y132900D01*
Y120500D01*
X144200Y111000D01*
Y86865D01*
G03X144198Y86800I1599J-82D01*
G01Y85200D01*
G03X144200Y85135I1601J17D01*
G01Y83265D01*
G03X144198Y83200I1599J-82D01*
G01Y81600D01*
G03X144200Y81535I1601J17D01*
G01Y79565D01*
G03X144198Y79500I1599J-82D01*
G01Y77900D01*
G03X144200Y77835I1601J17D01*
G01Y76800D01*
X142600Y75200D01*
X129000D01*
X127700Y76500D01*
Y87100D01*
X126877Y87923D01*
X126929Y88047D01*
G03X126457Y90457I-2029J854D01*
G01X126038Y90876D01*
G02X126117Y91503I283J283D01*
G03X126557Y94957I-1117J1897D01*
G01X125748Y95766D01*
X125600D01*
Y101254D01*
G03Y104946I-1200J1846D01*
G37*
G36*
G01X168300Y187198D02*
G03X168484Y187209I-3J1602D01*
G01X168580Y187220D01*
X168998Y186802D01*
Y185500D01*
G03X169200Y184722I1602J1D01*
G01Y178800D01*
X167200Y176800D01*
X161900D01*
X161600Y177100D01*
Y185700D01*
X162398Y186498D01*
X165398D01*
X166180Y187281D01*
X166291Y187252D01*
G03X166700Y187198I412J1548D01*
G01X168300D01*
G37*
G36*
G01X159300Y187700D02*
X155300Y191700D01*
Y207368D01*
G02X155930Y207695I400J0D01*
G03Y213093I1903J2699D01*
G02X155300Y213420I-230J327D01*
G01Y214500D01*
X156600Y215800D01*
X159580D01*
G03X163966I2193J2469D01*
G01X164100D01*
X165900Y214000D01*
Y199418D01*
X165895Y199395D01*
G03X165852Y199030I1559J-369D01*
G01Y197630D01*
G03X167086Y196071I1602J0D01*
G01X167142Y196058D01*
X168501Y194698D01*
X173002D01*
X173700Y194000D01*
Y189700D01*
X172500Y188500D01*
X172065D01*
G03X172000Y188502I-82J-1599D01*
G01X170600D01*
G03X170535Y188500I17J-1601D01*
G01X165700D01*
X164900Y187700D01*
X159300D01*
G37*
G36*
G01X432839Y83327D02*
X432510Y82998D01*
X427551D01*
X427542Y82999D01*
G03X427396Y83006I-150J-1595D01*
G01X425996D01*
G03X425850Y82999I4J-1602D01*
G01X425841Y82998D01*
X412051D01*
X411896Y83153D01*
Y93496D01*
X417200Y98800D01*
X429300D01*
X429749Y98351D01*
Y86651D01*
X430785Y85615D01*
X430792Y85622D01*
X432566D01*
X432848Y85340D01*
X432840Y85246D01*
G03X432832Y85095I1594J-160D01*
G01Y83495D01*
G03X432834Y83415I1601J0D01*
G01X432839Y83327D01*
G37*
G36*
G01X423900Y100900D02*
X423100Y101700D01*
Y105200D01*
X431700Y113800D01*
X435438D01*
X435470Y113789D01*
G03X436000Y113698I532J1511D01*
G01X437400D01*
G03X437584Y113709I-3J1602D01*
G01X437680Y113720D01*
X438100Y113300D01*
Y106100D01*
X432900Y100900D01*
X423900D01*
G37*
G36*
G01X459040Y59277D02*
X458686Y58923D01*
X451480D01*
X451232Y59171D01*
Y59338D01*
Y60976D01*
Y61865D01*
X453758Y64392D01*
X454579D01*
X454585Y64398D01*
X454762D01*
X455162Y63998D01*
Y62426D01*
X456237Y61351D01*
X458640D01*
G02X459040Y60943I0J-400D01*
G01Y59277D01*
G37*
G36*
G01X456057Y69573D02*
X455866Y69764D01*
Y72476D01*
X455622Y72720D01*
X450009D01*
X449790Y72939D01*
Y77139D01*
X449642Y77287D01*
Y79608D01*
X454034D01*
X455636Y78006D01*
Y77965D01*
X461159D01*
X462372Y76752D01*
Y69758D01*
X462187Y69573D01*
X456057D01*
G37*
G36*
G01X453900Y66607D02*
X452524Y65231D01*
X451076D01*
X450561Y65746D01*
Y65830D01*
G03X450562Y65841I-1588J150D01*
G01Y67241D01*
G03X450552Y67414I-1602J-6D01*
G01X450551Y67424D01*
Y69059D01*
G03X450765Y71018I-2287J1241D01*
G01X450732Y71131D01*
X451062Y71461D01*
X453190D01*
X453900Y70751D01*
Y66607D01*
G37*
G36*
G01X467472Y62374D02*
X466138Y63708D01*
X465846D01*
Y68474D01*
X472550D01*
X473004Y68020D01*
Y57863D01*
X469496Y54355D01*
X467715D01*
X466948Y55122D01*
Y57452D01*
X467472Y57977D01*
Y58337D01*
X467508Y58388D01*
G03X467792Y59300I-1317J910D01*
G01Y60900D01*
G03X467508Y61812I-1601J2D01*
G01X467472Y61863D01*
Y62374D01*
G37*
G36*
G01X560662Y162038D02*
X554550Y168150D01*
Y170450D01*
X554700Y170600D01*
Y187215D01*
G02X555456Y187397I400J0D01*
G03X567283Y190071I5568J2864D01*
G01X567286Y190168D01*
Y190266D01*
Y190356D01*
X567283Y190451D01*
G03X555456Y193125I-6259J-190D01*
G02X554700Y193307I-356J182D01*
G01Y203766D01*
G02X555456Y203948I400J0D01*
G03Y209636I5568J2844D01*
G02X554700Y209818I-356J182D01*
G01Y227300D01*
X552250Y229750D01*
X550900Y228400D01*
X515700D01*
X513000Y225700D01*
X490100D01*
X478300Y213900D01*
X464800D01*
X462500Y216200D01*
Y237287D01*
X464200Y238987D01*
X602308D01*
G02X602968Y238713I-2J-936D01*
G01X612473Y229208D01*
G02X612747Y228548I-662J-662D01*
G01Y163248D01*
G02X611811Y162312I-936J0D01*
G01X562596D01*
G03X560774Y162068I2J-6938D01*
G01X560662Y162038D01*
G37*
G36*
G01X512000Y208200D02*
X493800D01*
X492800Y209200D01*
Y219400D01*
X495000Y221600D01*
X511000D01*
X512550Y220050D01*
Y208750D01*
X512000Y208200D01*
G37*
G36*
G01X520833Y63852D02*
X520673Y64752D01*
G03X520640Y64913I-3172J-566D01*
G01X520639Y64918D01*
X520600Y65138D01*
Y90600D01*
X526900Y96900D01*
X550400D01*
X554900Y92400D01*
Y9600D01*
X548600Y3300D01*
X540100D01*
X537000Y200D01*
Y-34300D01*
X535500Y-35800D01*
X531337D01*
X531322Y-35798D01*
G03X530994Y-35774I-326J-2202D01*
G01X528097D01*
X528070Y-35800D01*
X527835D01*
X527808Y-35774D01*
X524994D01*
G03X524666Y-35798I-2J-2226D01*
G01X524651Y-35800D01*
X522100D01*
X520600Y-34300D01*
Y42864D01*
X520833Y63852D01*
G37*
G36*
G01X535300Y181600D02*
X532400Y184500D01*
Y186800D01*
X532700Y187100D01*
Y202000D01*
X526300Y208400D01*
X518500D01*
X517500Y209400D01*
Y225600D01*
X518299Y226398D01*
X551729D01*
X551859Y226528D01*
G02X552200Y226387I141J-142D01*
G01Y187700D01*
X546100Y181600D01*
X535300D01*
G37*
%LPC*%
G75*
G36*
G01X104273Y190047D02*
Y189247D01*
X104267Y188905D01*
Y188105D01*
X103467D01*
Y188905D01*
X103473Y189247D01*
Y190047D01*
X104273D01*
G37*
G36*
G01X110273D02*
Y189247D01*
X110267Y188905D01*
Y188105D01*
X109467D01*
Y188905D01*
X109473Y189247D01*
Y190047D01*
X110273D01*
G37*
G36*
G01X164700Y185900D02*
X165500D01*
X166700Y185200D01*
Y184400D01*
X165900D01*
X164700Y185100D01*
Y185900D01*
G37*
G36*
G01X165500Y191500D02*
X165900Y191200D01*
X166700D01*
Y190400D01*
X165900D01*
X165500Y190700D01*
X164700D01*
Y191500D01*
X165500D01*
G37*
G54D84*
X147800Y84200D03*
X141800D03*
G54D85*
X599868Y229462D03*
X540347Y32747D03*
G54D83*
X122403Y148109D03*
Y138269D03*
X126338Y130394D03*
X130278Y228109D03*
X122403Y218269D03*
X126338Y210394D03*
X130278Y218269D03*
X142088Y155984D03*
X146023Y148109D03*
X149963Y155984D03*
X153898Y148109D03*
X157833Y155984D03*
X142088Y130394D03*
X146023Y138269D03*
X149963Y130394D03*
X153898Y138269D03*
X146023Y228109D03*
X153898D03*
X146023Y218269D03*
X149963Y210394D03*
G54D82*
X14794Y226306D03*
X585785Y228866D03*
X542107Y17432D03*
G54D86*
X539370Y190256D03*
Y206792D03*
G54D81*
X25750Y78250D03*
X105078Y227717D03*
X107278D03*
X92701Y230711D03*
X96101D03*
X97460Y230724D03*
X100860D03*
X87848Y230826D03*
X91248D03*
X82931Y230840D03*
X86331D03*
X93285Y105975D03*
X96685D03*
X98000Y106000D03*
X101400D03*
X87100Y50100D03*
X83700D03*
X107700Y44600D03*
X109900D03*
X37850Y78250D03*
X83700Y41100D03*
X87100D03*
X103788Y182278D03*
Y184678D03*
X103867Y186105D03*
X103873Y192047D03*
X88278Y128633D03*
X91678D03*
X93285Y111575D03*
X96685D03*
X98000Y111600D03*
X101400D03*
X93285Y114975D03*
X96685D03*
X98000Y115000D03*
X101400D03*
X88278Y119633D03*
X91678D03*
X93368Y119688D03*
X96768D03*
X92701Y221711D03*
X96101D03*
X97460Y221724D03*
X100860D03*
X87848Y221826D03*
X91248D03*
X82931Y221840D03*
X86331D03*
X173100Y105500D03*
Y102100D03*
X171800Y106700D03*
Y109100D03*
X147800Y79900D03*
Y81200D03*
X155400Y86100D03*
X158800D03*
X147800Y87200D03*
X164100Y102100D03*
Y105500D03*
X165800Y106700D03*
Y109100D03*
X141800Y77500D03*
Y79900D03*
Y81200D03*
Y87200D03*
X109788Y184678D03*
X109867Y186105D03*
X109873Y192047D03*
X165100Y182100D03*
X170200Y190700D03*
X168700Y190800D03*
X161700Y191100D03*
X163654Y197230D03*
Y199430D03*
X417344Y85147D03*
X419544D03*
X413183Y85176D03*
X415383D03*
X421538D03*
X423738D03*
X425596Y85204D03*
X427796D03*
X426327Y87010D03*
Y90410D03*
X435600Y111500D03*
X453631Y61376D03*
X452188Y75243D03*
X453095Y76676D03*
X452760Y67641D03*
X470191Y58900D03*
Y61300D03*
%LPD*%
G75*
G54D10*
G01X415019Y56060D02*
X409360D01*
X408800Y55500D01*
G01X404850Y54873D02*
X408173D01*
X408800Y55500D01*
G01X437419Y59997D02*
X441957D01*
X444736Y62776D01*
X445185D01*
G01X448881Y60176D02*
X446295Y62762D01*
X445199D01*
X445185Y62776D01*
G01X448264Y70300D02*
X445700D01*
X441700Y66300D01*
Y62820D01*
X440846Y61966D01*
X437419D01*
G01X448264Y70300D02*
X448268Y70296D01*
Y66599D01*
X448210Y66541D01*
X21800Y-41500D03*
X14794Y226306D03*
X168268Y143189D03*
Y223189D03*
X456258Y143189D03*
Y223189D03*
X542107Y17432D03*
X585785Y228866D03*
X610300Y-43600D03*
X612500Y540800D03*
G54D11*
X28000Y75500D03*
X63100Y82000D03*
X70700D03*
X35600Y75500D03*
X103000Y196800D03*
X110600D03*
G54D20*
X109200Y-26200D03*
Y-15200D03*
G54D30*
X102500Y65800D03*
X59600Y206900D03*
X133100Y56200D03*
X520600Y196600D03*
G54D21*
X85400Y48400D03*
X89978Y126933D03*
X95068Y126988D03*
X99160Y229024D03*
X89548Y229126D03*
X94401Y229011D03*
X84631Y229140D03*
X157100Y84400D03*
X434600Y21600D03*
G54D12*
G01X95906Y-63909D02*
Y-53300D01*
G01X126800Y-53409D02*
X126209Y-54000D01*
X125142D01*
X124252Y-54890D01*
Y-63909D01*
G01X135182Y-53409D02*
X133701Y-54890D01*
Y-63909D01*
G01X144631Y-53409D02*
X143150Y-54890D01*
Y-63909D01*
G01X154080Y-53409D02*
X152599Y-54890D01*
Y-63909D01*
G01X163529Y-53409D02*
X162048Y-54890D01*
Y-63909D01*
G01X172977Y-53409D02*
X171496Y-54890D01*
Y-63909D01*
G01X228189D02*
Y-54890D01*
X229670Y-53409D01*
G01X191875D02*
X190394Y-54890D01*
Y-63909D01*
G01X201324Y-53409D02*
X199843Y-54890D01*
Y-63909D01*
G01X210773Y-53409D02*
X209292Y-54890D01*
Y-63909D01*
G01X220221Y-53409D02*
X218740Y-54890D01*
Y-63909D01*
G01X239119Y-53409D02*
X237638Y-54890D01*
Y-63909D01*
G01X248568Y-53409D02*
X247087Y-54890D01*
Y-63909D01*
G01X258017Y-53409D02*
X256536Y-54890D01*
Y-63909D01*
G01X267466Y-53409D02*
X265985Y-54890D01*
Y-63909D01*
G01X276914Y-53409D02*
X275433Y-54890D01*
Y-63909D01*
G01X286363Y-53409D02*
X284882Y-54890D01*
Y-63909D01*
G01X305261Y-53409D02*
X303780Y-54890D01*
Y-63909D01*
G01X314710Y-53409D02*
X313229Y-54890D01*
Y-63909D01*
G01X324158Y-53409D02*
X322677Y-54890D01*
Y-63909D01*
G01X333607Y-53409D02*
X332126Y-54890D01*
Y-63909D01*
G01X343056Y-53409D02*
X341575Y-54890D01*
Y-63909D01*
G01X295812Y-53409D02*
X294331Y-54890D01*
Y-63909D01*
G01X352505Y-53409D02*
X351024Y-54890D01*
Y-63909D01*
G01X361954Y-53409D02*
X360473Y-54890D01*
Y-63909D01*
G01X371403Y-53409D02*
X369922Y-54890D01*
Y-63909D01*
G01X380851Y-53409D02*
X379370Y-54890D01*
Y-63909D01*
G01X390300Y-53409D02*
X388819Y-54890D01*
Y-63909D01*
G01X399815Y-52741D02*
X398268Y-54288D01*
Y-63909D01*
G01X491949Y-64309D02*
Y-54972D01*
X493496Y-53425D01*
G01X502945D02*
X501398Y-54972D01*
Y-64309D01*
G01X484047Y-53425D02*
X482500Y-54972D01*
Y-64309D01*
G01X474598Y-53425D02*
X473051Y-54972D01*
Y-64309D01*
G01X465149Y-53425D02*
X463602Y-54972D01*
Y-64309D01*
G01X446252Y-53425D02*
X444705Y-54972D01*
Y-64309D01*
G01X455701Y-53425D02*
X454154Y-54972D01*
Y-64309D01*
G01X529744D02*
Y-54972D01*
X531291Y-53425D01*
G01X521842D02*
X520295Y-54972D01*
Y-64309D01*
G01X512393Y-53425D02*
X510846Y-54972D01*
Y-64309D01*
X25700Y89200D03*
X27207Y85293D03*
X24400Y81900D03*
X22300Y85000D03*
X21800Y78600D03*
X21600Y74000D03*
X28200Y160400D03*
X95906Y-53300D03*
X84619Y-27663D03*
X89467Y-47981D03*
X84671Y-44973D03*
X79444Y-46817D03*
X90546Y-41425D03*
X90332Y-30191D03*
X85442Y-39927D03*
X79444Y-41282D03*
X90400Y-36500D03*
X85231Y-34026D03*
X79035Y-30696D03*
X79103Y-35748D03*
X107800Y4300D03*
X107000Y-49000D03*
X106800Y-53000D03*
X107100Y-36900D03*
X107500Y-33200D03*
X76300Y79700D03*
X78900Y82400D03*
X78200Y76200D03*
X78300Y72600D03*
X78400Y68900D03*
X74700Y73100D03*
X73500Y76600D03*
X74900Y65800D03*
X74800Y69500D03*
X71000Y73500D03*
X67400Y76200D03*
X71100Y69800D03*
X67200Y72400D03*
Y68800D03*
X83400Y55300D03*
X72400Y22300D03*
X90100Y23100D03*
X64200Y99200D03*
X78000Y99900D03*
X87300Y55300D03*
X75500Y55400D03*
X79099Y55280D03*
X33200Y98700D03*
X30600Y88100D03*
X33700Y91400D03*
X29400Y92300D03*
X32800Y95000D03*
X102000Y40300D03*
X103000Y28300D03*
X105800Y40200D03*
X107000Y28300D03*
X96000Y80100D03*
X97800Y76800D03*
X93000Y73300D03*
X93800Y77000D03*
X89800Y76700D03*
X50700Y81900D03*
X58000Y81600D03*
X53000Y59800D03*
X49400Y60000D03*
X54300Y81700D03*
X71500Y39500D03*
X71700Y31500D03*
X69300Y36500D03*
X69400Y26700D03*
X86000Y36087D03*
X78600Y36200D03*
X74600Y36100D03*
X82300Y36200D03*
X64600Y104500D03*
X78000Y105800D03*
X32400Y160600D03*
X29200Y164000D03*
X33100Y164800D03*
X36000Y161800D03*
X31000Y156900D03*
X55600Y105100D03*
X54400Y110000D03*
X54600Y114900D03*
X59000Y107900D03*
X59700Y115200D03*
X44200Y212200D03*
X39200Y212100D03*
X44400Y217400D03*
X39300D03*
X111600Y4100D03*
X115500Y4000D03*
X119300Y3800D03*
X123000D03*
X127000Y3900D03*
X130800Y4000D03*
X111300Y-49100D03*
X111100Y-53100D03*
X111400Y-37000D03*
X111800Y-33300D03*
X131266Y85081D03*
X135025Y85092D03*
X138722Y85144D03*
X131666Y78581D03*
X135425Y78592D03*
X139122Y78644D03*
X109600Y40000D03*
X110800Y28100D03*
X138922Y94844D03*
X135225Y94792D03*
X131466Y94781D03*
X172300Y94300D03*
X169800Y91100D03*
X174900Y90900D03*
X152700Y33300D03*
X152279Y36876D03*
X153000Y40700D03*
X167100Y181200D03*
X163300Y178900D03*
X135100Y161900D03*
X155600Y166300D03*
X151700D03*
X134900Y165700D03*
X146165Y120044D03*
X140552Y117907D03*
X136626Y118116D03*
X158100Y116300D03*
X158000Y120900D03*
Y124800D03*
X142500Y203900D03*
X145300Y201100D03*
X148314Y203751D03*
X162100Y193800D03*
X165700Y195000D03*
X363700Y78200D03*
X421405Y90902D03*
X418437Y87727D03*
X423690Y87875D03*
X428500Y107700D03*
X424200Y103800D03*
X453500Y-9800D03*
X449900Y-9700D03*
X453400Y-13500D03*
X449800D03*
X453500Y-5700D03*
X449900D03*
X453600Y-2000D03*
X450000Y-1900D03*
X460535Y76560D03*
X456662Y76376D03*
X432100Y103800D03*
X495500Y219600D03*
Y210500D03*
X495400Y215300D03*
X500200Y219500D03*
X504800Y219600D03*
X504500Y210600D03*
X500200Y210400D03*
X504700Y215300D03*
X500100Y215200D03*
X540500Y219500D03*
X532200Y219300D03*
X527000Y219500D03*
X519900D03*
G54D31*
X102500Y69400D03*
X59600Y210500D03*
X133100Y59800D03*
X520600Y200200D03*
G54D13*
X15748Y128150D03*
X542913D03*
G54D40*
X104675Y92764D03*
X79179Y140287D03*
X521920Y181702D03*
G54D22*
X85400Y42800D03*
X89978Y121333D03*
X95068Y121388D03*
X99160Y223424D03*
X89548Y223526D03*
X94401Y223411D03*
X84631Y223540D03*
X157100Y78800D03*
X434600Y16000D03*
G54D32*
X91600Y91200D03*
X65600Y139400D03*
X170600Y107900D03*
X108667Y187305D03*
X108673Y190847D03*
X108588Y183478D03*
X404900Y54873D03*
X404961Y51269D03*
X407955Y65607D03*
X366800Y72500D03*
X461441Y60110D03*
X527900Y196300D03*
G54D23*
X47930Y92365D03*
X50813Y95248D03*
X48691Y149395D03*
X51535Y152305D03*
G54D50*
X157100Y62300D03*
X143000Y86000D03*
Y82400D03*
Y78700D03*
X289000Y196800D03*
X365600Y35400D03*
X408700Y33400D03*
X447520Y33313D03*
X465391Y60100D03*
X447388Y74043D03*
X450400Y44300D03*
X431634Y84295D03*
X448831Y60176D03*
X513082Y198350D03*
G54D14*
G01X-84798Y-164972D02*
Y-244972D01*
G01D02*
X1172402D01*
G01X-88798Y-148972D02*
G02I-12000J0D01*
G01X-93948D02*
G02I-6850J0D01*
G01X-100798Y-164972D02*
Y-132972D01*
G01X-84798Y-148972D02*
X-116798D01*
G01X-84798Y-164972D02*
X1172402D01*
G01X-84798Y-200472D02*
X1172402D01*
G01X111800Y17950D02*
X107700D01*
X107600Y17850D01*
G01X90700Y97150D02*
X92250Y95600D01*
X93600D01*
X93900Y95300D01*
G01X102500Y65850D02*
X99950D01*
X98300Y67500D01*
G01X65300Y143350D02*
X62450D01*
X62000Y142900D01*
G01X62050Y139400D02*
Y142850D01*
X62000Y142900D01*
G01X98139Y135908D02*
X101500D01*
G01X98139D02*
Y140032D01*
X98135Y140036D01*
G01X62700Y150100D02*
Y153450D01*
X63400Y154150D01*
G01X68800Y139000D02*
X68400Y139400D01*
X65550D01*
G01X59300Y154250D02*
Y151100D01*
X59400Y151000D01*
G01X67500Y154150D02*
X66100Y152750D01*
Y151000D01*
G01X67750Y163800D02*
Y160700D01*
G01X99405Y144059D02*
X101500Y141964D01*
Y139900D01*
G01X83300Y158450D02*
X80450D01*
X80000Y158900D01*
G01X95700Y172350D02*
X98900D01*
G01X95700Y161350D02*
X94150D01*
X92400Y163100D01*
G01X80400Y167200D02*
Y165900D01*
X78750Y164250D01*
Y163800D01*
G01X98126Y131798D02*
X102202D01*
G01X56400Y164250D02*
X56250Y164400D01*
Y168300D01*
G01X59400Y151000D02*
Y149200D01*
X61500Y147100D01*
X65050D01*
X65300Y146850D01*
G01X59600Y210450D02*
Y214000D01*
G01X55900Y206950D02*
X56500Y206350D01*
Y202900D01*
G01X59600Y206950D02*
Y201500D01*
G01X55900Y206950D02*
X59600D01*
G01X91700Y210450D02*
X95900D01*
G01X87500D02*
X91700D01*
G01X83500D02*
X87500D01*
G01X79500D02*
X83500D01*
G01X75500D02*
X79500D01*
G01X71500D02*
X75500D01*
G01X95900D02*
X99350D01*
X100500Y209300D01*
G01X153300Y22300D02*
X156300Y19300D01*
Y18650D01*
G01X140300Y22300D02*
X113300D01*
X111800Y20800D01*
Y17950D01*
G01X121248Y89357D02*
X124443D01*
X124900Y88900D01*
G01X142400Y66700D02*
X137300D01*
X134000Y63400D01*
G01X157100Y78600D02*
X157000D01*
G01D02*
Y74250D01*
G01X147900Y73800D02*
X152700Y78600D01*
X157000D01*
G01X142400Y24400D02*
X140300Y22300D01*
G01X137000Y56350D02*
Y61500D01*
X137400Y61900D01*
G01X133100Y56250D02*
X136900D01*
X137000Y56350D01*
G01X121270Y93564D02*
X124836D01*
X125000Y93400D01*
G01X130278Y134767D02*
Y138269D01*
G01D02*
Y141771D01*
G01X126776Y138269D02*
X130278D01*
G01X126338Y126892D02*
Y130394D01*
G01D02*
Y133896D01*
G01X122836Y130394D02*
X126338D01*
G01D02*
X129840D01*
G01X122403Y134767D02*
Y138269D01*
G01D02*
Y141771D01*
G01X118901Y138269D02*
X122403D01*
G01D02*
X125905D01*
G01X130278Y144607D02*
Y148109D01*
G01D02*
Y151611D01*
G01X126776Y148109D02*
X130278D01*
G01X126338Y152482D02*
Y155984D01*
G01D02*
X129840D01*
G01X149963Y126892D02*
Y130394D01*
G01D02*
Y133896D01*
G01X146461Y130394D02*
X149963D01*
G01D02*
X153465D01*
G01X157833Y152482D02*
Y155984D01*
G01D02*
Y159486D01*
G01X154331Y155984D02*
X157833D01*
G01D02*
X161335D01*
G01X153898Y144607D02*
Y148109D01*
G01D02*
Y151611D01*
G01X150396Y148109D02*
X153898D01*
G01D02*
X157400D01*
G01X157833Y126892D02*
Y130394D01*
G01D02*
X161335D01*
G01X130278Y214767D02*
Y218269D01*
G01D02*
Y221771D01*
G01X126776Y218269D02*
X130278D01*
G01D02*
X133780D01*
G01X126338Y206892D02*
Y210394D01*
G01D02*
Y213896D01*
G01X122836Y210394D02*
X126338D01*
G01D02*
X129840D01*
G01X122403Y214767D02*
Y218269D01*
G01D02*
Y221771D01*
G01X118901Y218269D02*
X122403D01*
G01D02*
X125905D01*
G01X130278Y224607D02*
Y228109D01*
G01D02*
Y231611D01*
G01X126776Y228109D02*
X130278D01*
G01D02*
X133780D01*
G01X126338Y232482D02*
Y235984D01*
G01X122836D02*
X126338D01*
G01D02*
X129840D01*
G01X149963Y206892D02*
Y210394D01*
G01D02*
Y213896D01*
G01X146461Y210394D02*
X149963D01*
G01D02*
X153465D01*
G01X157833Y232482D02*
Y235984D01*
G01X154331D02*
X157833D01*
G01D02*
X161335D01*
G01X153898Y224607D02*
Y228109D01*
G01D02*
Y231611D01*
G01X150396Y228109D02*
X153898D01*
G01D02*
X157400D01*
G01X157833Y206892D02*
Y210394D01*
G01D02*
Y213896D01*
G01Y210394D02*
X161335D01*
G01X242950Y176500D02*
Y180600D01*
G01X242800Y200600D02*
Y199352D01*
X243148Y199004D01*
Y197300D01*
G01X243000Y185300D02*
X244100Y184900D01*
X246350D01*
G01X230500Y191400D02*
Y191000D01*
X233500Y188000D01*
G01X243150Y189000D02*
X241500D01*
X240500Y188000D01*
X233500D01*
G01X234150Y198500D02*
X233386D01*
X230084Y195198D01*
G01X243150Y189000D02*
Y193200D01*
G01X230084Y195198D02*
Y193500D01*
X230500Y193084D01*
Y191400D01*
G01X209400Y200100D02*
Y197822D01*
X209700Y197522D01*
Y196650D01*
X210550Y195800D01*
G01X286850Y168400D02*
Y164850D01*
X289600Y162100D01*
G01X296850Y167600D02*
Y171800D01*
G01X307000Y174650D02*
Y172700D01*
X308600Y171100D01*
G01X307000Y174650D02*
X301300D01*
X301100Y174850D01*
G01X289600Y162100D02*
X293200D01*
X296850Y165750D01*
Y167600D01*
G01X295800Y195900D02*
X294900Y196800D01*
X292550D01*
G01X302061Y198009D02*
Y199139D01*
X299800Y201400D01*
X294700D01*
X294600Y201300D01*
G01X307000Y185650D02*
X306350Y186300D01*
X301500D01*
G01X294600Y201300D02*
X291700D01*
X289050Y198650D01*
Y196800D01*
G01X301500Y186300D02*
X301400Y186400D01*
X298250D01*
X296850Y187800D01*
G01X384902Y-164972D02*
Y-244972D01*
G01X352600Y7600D02*
X356500Y3700D01*
Y1850D01*
X360150Y-1800D01*
G01X411450Y2452D02*
X412398Y3400D01*
X415100D01*
G01X404330Y868D02*
X408768D01*
X410352Y2452D01*
X411450D01*
G01X404330Y4368D02*
X400382D01*
X400200Y4550D01*
G01X404330Y4368D02*
X404400Y4438D01*
Y7200D01*
G01X413800Y11750D02*
X423450D01*
X428600Y16900D01*
G01X404330Y4368D02*
X405768D01*
X413150Y11750D01*
X413800D01*
G01X426919Y34674D02*
X426445Y34200D01*
X423500D01*
G01X404405Y65607D02*
X404200Y65812D01*
Y71362D01*
X405569Y72731D01*
G01X401411Y51269D02*
Y46789D01*
X401211Y46589D01*
G01X401350Y54873D02*
Y51330D01*
X401411Y51269D01*
G01X363700Y78200D02*
X364300D01*
X366750Y75750D01*
Y72500D01*
G01X404500Y47769D02*
Y50858D01*
X404911Y51269D01*
G01X426919Y38174D02*
X426545Y37800D01*
X423500D01*
G01X407905Y65607D02*
X408149Y65851D01*
Y68549D01*
X409400Y69800D01*
G01X433900Y11000D02*
X434600Y11700D01*
Y15800D01*
G01X437300Y91100D02*
X435579Y89379D01*
X434496D01*
X433827Y88710D01*
G01X439418Y29585D02*
Y26110D01*
G01X433827Y88710D02*
X435184Y87353D01*
Y84295D01*
G01X457400Y41700D02*
X458050Y41050D01*
Y37100D01*
G01X457400Y41700D02*
X455000Y44100D01*
X454150D01*
X453950Y44300D01*
G01X457400Y41800D02*
Y41700D01*
G01X435287Y29558D02*
Y25646D01*
G01X441688Y74914D02*
X441803D01*
X445265Y78376D01*
X445595D01*
G01X434600Y21800D02*
Y24959D01*
X435287Y25646D01*
G01X445595Y78376D02*
X447438Y76533D01*
Y74043D01*
G01X450400Y40550D02*
X450065Y40885D01*
Y43915D01*
X450450Y44300D01*
G01X449400Y26433D02*
X450978Y28011D01*
Y29487D01*
G01X522402Y-164972D02*
Y-244972D01*
G01X524000Y200000D02*
X524950Y199050D01*
Y196900D01*
X524350Y196300D01*
G01X520600Y200150D02*
X523850D01*
X524000Y200000D01*
G01X561024Y200340D02*
Y206792D01*
G01D02*
Y213244D01*
G01Y206792D02*
X567476D01*
G01X520936Y191100D02*
X520970Y191134D01*
Y192569D01*
G01X520600Y196650D02*
X520900Y196350D01*
Y194654D01*
X520970Y194584D01*
Y192569D01*
G01X528500Y200000D02*
X528450Y199950D01*
Y196900D01*
X527850Y196300D01*
G01X539370Y200340D02*
Y206792D01*
G01D02*
Y213244D01*
G01X532918Y206792D02*
X539370D01*
G01D02*
X545822D01*
G01X539370Y183804D02*
Y190256D01*
G01D02*
Y196708D01*
G01X532918Y190256D02*
X539370D01*
G01D02*
X545822D01*
G01X637402Y-164972D02*
Y-244972D01*
G01X804902Y-164972D02*
Y-244972D01*
G01X974902Y-164972D02*
Y-244972D01*
G01X1172402Y-164972D02*
Y-244972D01*
G01X1200402Y-148972D02*
G02I-12000J0D01*
G01X1195252D02*
G02I-6850J0D01*
G01X1188402Y-164972D02*
Y-132972D01*
G01X1204402Y-148972D02*
X1172402D01*
X6487Y175762D03*
Y165762D03*
X14947Y175971D03*
Y165971D03*
X22700Y190800D03*
X26300D03*
X26600Y201000D03*
X23000D03*
X6487Y235762D03*
X25453Y235870D03*
X15453D03*
X6487Y225762D03*
Y215762D03*
Y205762D03*
Y195762D03*
Y185762D03*
X14947Y195971D03*
Y185971D03*
X92940Y6625D03*
X99000Y13800D03*
X99200Y18100D03*
X107400Y11300D03*
X98200Y10000D03*
X94042Y9842D03*
X93900Y95300D03*
X104600Y95000D03*
X102400Y92600D03*
X106800Y92700D03*
X104600Y90500D03*
X45800Y54800D03*
X45200Y89400D03*
X30700Y56400D03*
X98300Y72000D03*
X39900Y72800D03*
X87900Y94500D03*
X87250Y100650D03*
X98300Y67500D03*
X104500Y56200D03*
X88000Y65200D03*
X83200Y60000D03*
X48800Y87100D03*
X62000Y142900D03*
X56300Y180000D03*
X101500Y135908D03*
X62700Y150100D03*
X69000Y143300D03*
X79000Y142500D03*
X77000Y140300D03*
X81300Y140400D03*
X79200Y138100D03*
X104743Y174953D03*
X98900Y126800D03*
X85700Y129900D03*
X85900Y126300D03*
X81700Y129700D03*
X81800Y125900D03*
X68800Y139000D03*
X59400Y151000D03*
X56400Y164250D03*
X67750Y160700D03*
X66100Y151000D03*
X98900Y172350D03*
X92400Y163100D03*
X80000Y158900D03*
X80400Y167200D03*
X102202Y131798D03*
X101500Y139900D03*
X100000Y175700D03*
X105500Y109500D03*
X105400Y153600D03*
X106500Y149000D03*
X105218Y137218D03*
X71500Y168500D03*
X100800Y189700D03*
X100700Y182900D03*
X98400Y233100D03*
X59600Y214000D03*
X100700Y186300D03*
X35453Y235870D03*
X45453D03*
X55453D03*
X65453D03*
X75453D03*
X84400Y232900D03*
X89600D03*
X94900Y233000D03*
X56500Y202900D03*
X100500Y209300D03*
X75591Y202676D03*
X79843D03*
X83500Y189000D03*
X96000Y192000D03*
X72200Y202400D03*
X67500Y213500D03*
X64000D03*
X161100Y13600D03*
X126800Y-53409D03*
X135182D03*
X144631D03*
X154080D03*
X163529D03*
X172977D03*
X116900Y-35400D03*
X121801Y16999D03*
X146600Y3400D03*
X159450Y8750D03*
X160400Y4900D03*
X111018Y11382D03*
X148300Y16700D03*
X147878Y13326D03*
X182000Y66700D03*
X174400Y32500D03*
X176300Y45200D03*
X159450Y97400D03*
X151150Y83500D03*
X124900Y88900D03*
X161800Y71100D03*
X117200Y65750D03*
X116900Y59450D03*
X134000Y63400D03*
X151550Y87500D03*
X132600Y39900D03*
X147900Y73800D03*
X153300Y22300D03*
X137400Y61900D03*
X125000Y93400D03*
X129400Y62200D03*
X169800Y39200D03*
X161400Y58700D03*
X154300Y56400D03*
X124100Y78900D03*
X137900Y49400D03*
X110781Y87200D03*
X111750Y98450D03*
X152900Y46500D03*
X114850Y95650D03*
X181700Y72700D03*
X161694Y55106D03*
X154300Y49600D03*
X156600Y109800D03*
X152650D03*
X148950Y109600D03*
X116100Y169700D03*
X120400Y169800D03*
X125300Y170200D03*
X111800Y113700D03*
X117600Y117700D03*
X116176Y156724D03*
X109500Y168752D03*
X180076Y179876D03*
X175600Y166800D03*
X121700Y117300D03*
X111924Y156724D03*
X109500Y164500D03*
X172000Y166800D03*
X124400Y103100D03*
X181400Y124500D03*
X172300Y192800D03*
X164200Y205100D03*
X180300Y187200D03*
X179900Y191300D03*
X180000Y198500D03*
Y183500D03*
X183683Y198517D03*
X173300Y204969D03*
X240100Y20900D03*
X221900Y5100D03*
X235600Y5300D03*
X247200Y5400D03*
X195200Y5700D03*
X191875Y-53409D03*
X201324D03*
X210773D03*
X220221D03*
X229670D03*
X239119D03*
X248568D03*
X258017D03*
X267466D03*
X252300Y22200D03*
X255900Y35000D03*
X246500Y47900D03*
X200500Y31500D03*
X216300Y46700D03*
X226600Y21400D03*
X198300Y73200D03*
X196400Y91600D03*
X193900Y51600D03*
X202800Y50200D03*
X218900Y65600D03*
X198900Y21200D03*
X230300Y45100D03*
X233800Y66000D03*
X199400Y81400D03*
X236900Y85800D03*
X233700Y54400D03*
X262400Y169900D03*
X202300Y165100D03*
X196850Y177950D03*
X246800Y112500D03*
X198300Y111700D03*
X188900Y173300D03*
X225100Y168100D03*
X199900Y161600D03*
X192200Y166700D03*
X195900Y162100D03*
X242800Y200600D03*
X243000Y185300D03*
X239400Y191500D03*
X191600Y185600D03*
X209400Y200100D03*
X225600Y185900D03*
X230500Y191400D03*
X224100Y200100D03*
X256747Y199700D03*
X250100Y193000D03*
X267500Y182000D03*
X266000Y185100D03*
X254900Y188300D03*
X345042Y-41479D03*
X339942D03*
X324642D03*
X334842D03*
X329742D03*
X319070Y-41541D03*
X276914Y-53409D03*
X286363D03*
X295812D03*
X305261D03*
X314710D03*
X324158D03*
X333607D03*
X343056D03*
X324021Y-46464D03*
X334221D03*
X344421D03*
X320021D03*
X330221D03*
X340421D03*
X329242Y-36479D03*
X339442D03*
X325242D03*
X335442D03*
X345642D03*
X328000Y30500D03*
Y59000D03*
X339649Y41539D03*
X329400Y50300D03*
X339100Y73300D03*
X324600Y36900D03*
X343524Y36971D03*
X346000Y34640D03*
X300800Y100100D03*
X337900Y46800D03*
X346150Y84800D03*
X328655Y170950D03*
X313400Y119100D03*
X289600Y162100D03*
X308600Y171100D03*
X274400Y161700D03*
X327200Y178276D03*
Y174024D03*
X348200Y169900D03*
X326600Y182000D03*
X295800Y195900D03*
X294600Y201300D03*
X301500Y186300D03*
X332000Y192200D03*
X329400Y195900D03*
X334794Y195294D03*
X321600Y186300D03*
X323243Y183323D03*
X396042Y-41479D03*
X390942D03*
X380742D03*
X385842D03*
X375642D03*
X370542D03*
X365442D03*
X360342D03*
X355242D03*
X401142D03*
X350142D03*
X423852Y4375D03*
X420252Y-36925D03*
X410052Y-36825D03*
X380500Y17100D03*
X352505Y-53409D03*
X361954D03*
X371403D03*
X380851D03*
X390300D03*
X399815Y-52741D03*
X415100Y3400D03*
X352600Y7600D03*
X380200Y6800D03*
X380500Y13200D03*
X380200Y3300D03*
X354621Y-46464D03*
X364821D03*
X375021D03*
X385221D03*
X395421D03*
X350621D03*
X360821D03*
X371021D03*
X381221D03*
X391421D03*
X349642Y-36479D03*
X359842D03*
X370042D03*
X380242D03*
X390442D03*
X400642D03*
X355842D03*
X366042D03*
X376242D03*
X386442D03*
X396642D03*
X405500Y29200D03*
X370400Y88200D03*
X377800Y87800D03*
X383300Y50700D03*
X383500Y65800D03*
X388000Y41600D03*
X394500Y34000D03*
X380300Y21600D03*
X405800Y21100D03*
Y94200D03*
X405600Y87500D03*
X420322Y56072D03*
X423202Y56119D03*
X426128Y50188D03*
Y53348D03*
X426065Y56213D03*
X426113Y59046D03*
X425971Y62050D03*
X423500Y34200D03*
X416300Y37100D03*
X418705Y34695D03*
X405569Y72731D03*
X409026Y61211D03*
X383600Y55532D03*
X401211Y46589D03*
X373300Y35400D03*
X384000Y41600D03*
X391600Y29400D03*
X361600Y69100D03*
X383500Y69200D03*
X383600Y59618D03*
X383400Y46600D03*
X362400Y34500D03*
X404500Y36300D03*
X380200Y25800D03*
X349701Y64199D03*
X353100Y63900D03*
X359023Y47177D03*
X355370Y37411D03*
X355300Y81400D03*
X349700Y56000D03*
X349000Y28300D03*
X404500Y47769D03*
X409400Y69800D03*
X423500Y37800D03*
X412000Y29900D03*
X356700Y86600D03*
X353098Y55882D03*
X350300Y31800D03*
X352138Y50729D03*
X351500Y36100D03*
X355536Y50589D03*
X352700Y40000D03*
X355399Y47191D03*
X355300Y33900D03*
X391200Y35700D03*
X398805Y66200D03*
X408600Y27376D03*
X388006Y37706D03*
X395406Y66092D03*
X418650Y22850D03*
X408600Y23124D03*
X402500Y89124D03*
X375514Y85000D03*
X402500Y93376D03*
X372114Y85000D03*
X358700Y38100D03*
X362100D03*
X372400Y41100D03*
X436752Y4175D03*
X498052Y-625D03*
X490200Y-6400D03*
X488652Y-18225D03*
X496352Y-19025D03*
X432452Y-36225D03*
X447252Y-47725D03*
X445252Y-37225D03*
X455701Y-53425D03*
X502945D03*
X493496D03*
X484047D03*
X474598D03*
X465149D03*
X446252D03*
X433900Y11000D03*
X438900Y13400D03*
X428600Y16900D03*
X469300Y87600D03*
X459652Y31575D03*
X458100Y47300D03*
Y53700D03*
X448200Y93000D03*
X448369Y86631D03*
X432091Y56151D03*
X429056Y56135D03*
X457400Y41800D03*
X468588Y55981D03*
X431382Y35283D03*
X437300Y91100D03*
X454085Y63272D03*
X452496Y70099D03*
X454500Y29300D03*
X439418Y26110D03*
X439000Y87700D03*
X451381Y88210D03*
Y91719D03*
X435287Y25646D03*
X441688Y74914D03*
X449400Y26433D03*
X454000Y40600D03*
X429850Y22950D03*
X461513Y48758D03*
Y52267D03*
X452888Y108444D03*
X457097Y108548D03*
X457245Y105151D03*
X453736D03*
X466361Y230936D03*
X467506Y226106D03*
X502000Y229400D03*
X466010Y216328D03*
X492961Y227336D03*
X480761Y227936D03*
X505961Y236936D03*
X488161Y236336D03*
X479761D03*
X499761D03*
X455700Y205800D03*
X528590Y-12237D03*
Y2763D03*
X532137Y7890D03*
X532691Y-17725D03*
X531600Y-31800D03*
X523300Y-32100D03*
X531291Y-53425D03*
X521842D03*
X512393D03*
X524994Y-38000D03*
X530994D03*
X534737Y40290D03*
X534337Y52790D03*
X534637Y74290D03*
Y92590D03*
X532778Y21738D03*
X512000Y158400D03*
X511900Y174400D03*
Y142700D03*
X521900Y179500D03*
X548200Y169900D03*
X548300Y178100D03*
X578337Y166890D03*
X577748Y181113D03*
X529000Y158500D03*
X521600Y158400D03*
X520500Y154500D03*
X525000Y158000D03*
X551376Y176271D03*
Y172019D03*
X517900Y103300D03*
X524200Y181600D03*
X519700Y181900D03*
X521900Y184000D03*
X545300Y236800D03*
X529500Y236400D03*
X519761Y236336D03*
X537200Y236400D03*
X559761Y236336D03*
X579761D03*
X577748Y211113D03*
X578337Y226890D03*
X577748Y191113D03*
Y201113D03*
X524000Y200000D03*
X520970Y192569D03*
X528500Y200000D03*
X593337Y166890D03*
Y176890D03*
X608337Y166890D03*
Y176890D03*
X599761Y236336D03*
X593337Y206890D03*
Y216890D03*
Y226890D03*
Y186890D03*
Y196890D03*
X608337Y206890D03*
Y216890D03*
Y226890D03*
Y186890D03*
Y196890D03*
G54D41*
X71000Y100900D03*
Y120100D03*
G54D24*
X45526Y94769D03*
X48409Y97652D03*
X46287Y151799D03*
X49131Y154709D03*
G54D33*
X88000Y91200D03*
X62000Y139400D03*
X105067Y187305D03*
X105073Y190847D03*
X104988Y183478D03*
X167000Y107900D03*
X401300Y54873D03*
X401361Y51269D03*
X404355Y65607D03*
X363200Y72500D03*
X457841Y60110D03*
X524300Y196300D03*
G54D42*
X92700Y34400D03*
X103700D03*
X509994Y212056D03*
X520994D03*
G54D60*
X415019Y50154D03*
Y52123D03*
Y54091D03*
Y56060D03*
Y58029D03*
Y59997D03*
Y61966D03*
X437419D03*
Y59997D03*
Y58029D03*
Y56060D03*
Y54091D03*
Y52123D03*
Y50154D03*
G54D51*
X160700Y62300D03*
X146600Y86000D03*
Y82400D03*
Y78700D03*
X292600Y196800D03*
X369200Y35400D03*
X412300Y33400D03*
X451120Y33313D03*
X468991Y60100D03*
X450988Y74043D03*
X454000Y44300D03*
X435234Y84295D03*
X452431Y60176D03*
X516682Y198350D03*
G54D15*
X12100Y180900D03*
X28000Y216500D03*
X102800Y61700D03*
X92400Y85300D03*
X89100Y81000D03*
X50900Y166800D03*
X57400Y146000D03*
X54600Y140600D03*
X90972Y139034D03*
X91004Y134234D03*
X89700Y152300D03*
X93700Y149200D03*
X63400Y168300D03*
X62500Y161700D03*
X76613Y167516D03*
X88400Y158500D03*
X89500Y167700D03*
X70800Y152000D03*
X93200Y156000D03*
X87309Y163428D03*
X92100Y143700D03*
X74100Y221900D03*
X84400Y202800D03*
X89944Y202832D03*
X94900Y198600D03*
X60400Y187700D03*
X68200Y203200D03*
X63300Y203000D03*
X122500Y-6600D03*
X151800Y13100D03*
X142000Y-30200D03*
X110300Y36000D03*
X108600Y73000D03*
X117500Y79148D03*
X120000Y48500D03*
X152500Y67800D03*
X117400Y85048D03*
X109900Y53000D03*
X181800Y110500D03*
X116400Y103800D03*
X186688Y183400D03*
X185788Y188700D03*
X199500Y98100D03*
X251700Y171900D03*
X242100Y171200D03*
X250400Y189100D03*
X211888Y189000D03*
X335100Y31400D03*
X334700Y24369D03*
X339900Y35700D03*
X338100Y65400D03*
X334200Y47700D03*
X342900Y73200D03*
X289000Y176600D03*
X289600Y171800D03*
X319700Y178200D03*
X314000Y178400D03*
X292581Y179869D03*
X309500Y190300D03*
X321700Y190100D03*
X368700Y-1531D03*
X369900Y7300D03*
X391100Y4500D03*
X369700Y12700D03*
X369482Y17496D03*
X396000Y5000D03*
X419450Y16771D03*
X409550Y18971D03*
X411450Y-8329D03*
X408800Y55500D03*
X416500Y76200D03*
X409700Y77200D03*
X422556Y94629D03*
X369900Y23369D03*
X387800Y29800D03*
X380700Y74400D03*
X373000Y44900D03*
X372900Y50000D03*
X393768Y48100D03*
X373100Y55600D03*
X393900Y57900D03*
X389800Y73500D03*
X374800Y29516D03*
X375500Y74100D03*
X370351Y31320D03*
X370800Y72800D03*
X434525Y37420D03*
X444697Y41899D03*
X445185Y62776D03*
X448264Y70300D03*
X445063Y57977D03*
X463919Y56185D03*
X443396Y23617D03*
X444800Y37100D03*
X439800D03*
X508300Y229900D03*
X476797Y222299D03*
X524445Y71497D03*
X522293Y169769D03*
X515100Y169500D03*
X534700Y173200D03*
X537600Y169100D03*
X528800Y170000D03*
X509600Y220100D03*
X517100Y194600D03*
X509300Y198400D03*
G54D52*
X142400Y66700D03*
Y58700D03*
X151200Y62700D03*
G54D70*
X524430Y224202D03*
Y231802D03*
X532360Y224202D03*
Y231802D03*
X540290Y224202D03*
Y231802D03*
X548220Y224202D03*
Y231802D03*
G54D61*
X426219Y44860D03*
X424250D03*
X422282D03*
X420313D03*
Y67260D03*
X422282D03*
X424250D03*
X426219D03*
X432125Y44860D03*
X430156D03*
X428188D03*
Y67260D03*
X430156D03*
X432125D03*
G54D43*
X99700Y107700D03*
X94985Y107675D03*
X163400Y183800D03*
X428000Y97100D03*
G54D34*
X98700Y60700D03*
X95700Y179800D03*
Y164800D03*
X59300Y157700D03*
X106178Y226617D03*
X63400Y210400D03*
X67400D03*
X71500D03*
X83500D03*
X95900D03*
X55900D03*
X108800Y49100D03*
X116671Y111165D03*
X120998Y111171D03*
X181152Y170042D03*
X185182D03*
X234200Y171400D03*
X301100Y174800D03*
X307000Y178100D03*
X411450Y2402D03*
X400200Y4500D03*
X413800Y22700D03*
X395130Y81602D03*
X399360D03*
X443445Y33007D03*
X450400Y40500D03*
X435287Y33008D03*
X436700Y116000D03*
X526110Y165902D03*
X517530Y165802D03*
G54D25*
X39711Y97911D03*
X47489Y105689D03*
X38232Y154310D03*
X46010Y162088D03*
G54D16*
X25300Y195900D03*
X44500D03*
X134900Y103000D03*
X154100D03*
X141000Y177100D03*
X121800D03*
G54D80*
G01X424250Y67260D02*
Y70685D01*
X423841Y71094D01*
Y73207D01*
X422729Y74319D01*
Y75765D01*
X425109Y78145D01*
Y79067D01*
X426696Y80654D01*
G01X422282Y67260D02*
Y70629D01*
X422691Y71038D01*
Y72730D01*
X421579Y73842D01*
Y76242D01*
X422616Y77279D01*
Y77280D01*
X423959Y78623D01*
Y79305D01*
X422638Y80626D01*
G01X437419Y52123D02*
X440654D01*
X441063Y52532D01*
X442368D01*
X444981Y49919D01*
X448906D01*
X450356Y48469D01*
G01X437419Y54091D02*
X440654D01*
X441063Y53682D01*
X442845D01*
X445458Y51069D01*
X448875D01*
X450344Y52538D01*
G01X457245Y105151D02*
X456100Y104006D01*
Y83988D01*
X453946Y81834D01*
X443634D01*
X433684Y71884D01*
Y70818D01*
X434093Y70409D01*
Y67560D01*
G01X451381Y88210D02*
X450341Y89250D01*
X445932D01*
X429747Y73065D01*
Y70904D01*
X430156Y70495D01*
Y67260D01*
G01X453736Y105151D02*
X454950Y103937D01*
Y84465D01*
X453469Y82984D01*
X443157D01*
X432534Y72361D01*
Y70733D01*
X432125Y70324D01*
Y67260D01*
G01X451381Y91719D02*
X450062Y90400D01*
X445455D01*
X428597Y73542D01*
Y70904D01*
X428188Y70495D01*
Y67260D01*
G01X453856Y48469D02*
X455369Y49982D01*
X460289D01*
X461513Y48758D01*
G01Y52267D02*
X460378Y51132D01*
X455250D01*
X453844Y52538D01*
G01X532894Y-64309D02*
Y-59000D01*
G02X533154Y-58354I933J0D01*
G01X533893Y-57615D01*
Y-49883D01*
X528383Y-42594D01*
X527557Y-39046D01*
X527419Y-38450D01*
X526969Y-38000D01*
X524994D01*
G01X536043Y-64309D02*
Y-59100D01*
G03X535814Y-58386I-1228J0D01*
G01X535043Y-57615D01*
Y-49497D01*
X530379Y-43326D01*
X529448Y-42095D01*
X528929Y-39863D01*
X528679Y-38786D01*
Y-38340D01*
X529019Y-38000D01*
X530994D01*
G54D62*
X426219Y56060D03*
G54D53*
X108040Y59450D03*
X110600D03*
X113160D03*
Y65950D03*
X108040D03*
X125460Y65750D03*
X122900D03*
X120340D03*
Y59250D03*
X125460D03*
G54D71*
X539370Y190256D03*
Y206792D03*
X561024Y190256D03*
Y206792D03*
G54D44*
X99700Y113300D03*
X94985Y113275D03*
X163400Y189400D03*
X428000Y102700D03*
G54D26*
X90700Y100700D03*
X65300Y146900D03*
X167500Y189600D03*
X192000Y181500D03*
X404330Y4418D03*
X426919Y38224D03*
G54D35*
X98700Y57300D03*
X95700Y176400D03*
Y161400D03*
X59300Y154300D03*
X106178Y223217D03*
X63400Y207000D03*
X67400D03*
X71500D03*
X83500D03*
X95900D03*
X55900D03*
X108800Y45700D03*
X116671Y107765D03*
X120998Y107771D03*
X181152Y166642D03*
X185182D03*
X234200Y168000D03*
X301100Y171400D03*
X307000Y174700D03*
X411450Y-998D03*
X400200Y1100D03*
X413800Y19300D03*
X395130Y78202D03*
X399360D03*
X443445Y29607D03*
X450400Y37100D03*
X435287Y29608D03*
X436700Y112600D03*
X526110Y162502D03*
X517530Y162402D03*
G54D17*
X105355Y-63909D03*
X102205D03*
X99055D03*
X95906D03*
X92756D03*
X89607D03*
X86457D03*
X83307D03*
X80158D03*
X77008D03*
X174646D03*
X171496D03*
X168347D03*
X165197D03*
X162048D03*
X158898D03*
X155748D03*
X152599D03*
X149449D03*
X146300D03*
X143150D03*
X140000D03*
X136851D03*
X133701D03*
X130551D03*
X127402D03*
X124252D03*
X121103D03*
X117953D03*
X114803D03*
X111654D03*
X108504D03*
X265985D03*
X262835D03*
X259685D03*
X256536D03*
X253386D03*
X250237D03*
X247087D03*
X243937D03*
X240788D03*
X237638D03*
X234489D03*
X231339D03*
X228189D03*
X225040D03*
X221890D03*
X218740D03*
X215591D03*
X212441D03*
X209292D03*
X206142D03*
X202992D03*
X199843D03*
X196693D03*
X193544D03*
X190394D03*
X347874D03*
X344725D03*
X341575D03*
X338426D03*
X335276D03*
X332126D03*
X328977D03*
X325827D03*
X322677D03*
X319528D03*
X316378D03*
X313229D03*
X310079D03*
X306929D03*
X303780D03*
X300630D03*
X297481D03*
X294331D03*
X291181D03*
X288032D03*
X284882D03*
X281733D03*
X278583D03*
X275433D03*
X272284D03*
X269134D03*
X401418D03*
X398268D03*
X395118D03*
X391969D03*
X388819D03*
X385670D03*
X382520D03*
X379370D03*
X376221D03*
X373071D03*
X369922D03*
X366772D03*
X363622D03*
X360473D03*
X357323D03*
X354174D03*
X351024D03*
G54D72*
G01X98569Y93748D02*
X95452D01*
X93900Y95300D01*
G01X98569Y91780D02*
X92130D01*
X91550Y91200D01*
G01X98569Y95717D02*
X97883D01*
X92901Y100699D01*
X90749D01*
X90700Y100650D01*
G01X56300Y180000D02*
Y177250D01*
X55850Y176800D01*
G01X95700Y179850D02*
X90350D01*
X89237Y178737D01*
Y173644D01*
G01X95700Y179850D02*
X99350D01*
G01X69000Y143300D02*
Y142900D01*
X70629Y141271D01*
X73073D01*
G01X68800Y139000D02*
X69103Y139303D01*
X73073D01*
G01X146600Y3400D02*
Y2100D01*
X148742Y-42D01*
X150588D01*
G01X159450Y8750D02*
X158058Y7358D01*
X155708D01*
G01X181152Y166592D02*
X185182D01*
G01X188900Y173300D02*
Y168900D01*
X186592Y166592D01*
X185182D01*
G01X111800Y113700D02*
Y110632D01*
X112655Y109777D01*
G01X198100Y172408D02*
X189792D01*
X188900Y173300D01*
G01X225600Y185900D02*
X226100D01*
X232850Y179150D01*
X234300D01*
G01X234200Y167950D02*
X225100D01*
Y168100D01*
G01X239400Y191500D02*
X236000D01*
X234150Y193350D01*
Y194400D01*
G01X233500Y188000D02*
X240900Y180600D01*
X242950D01*
G01X192000Y181450D02*
X191600Y181850D01*
Y185600D01*
G01X341438Y2889D02*
X347889D01*
X352600Y7600D01*
G01X339649Y41539D02*
X341299Y39889D01*
X344638D01*
G01X404400Y7200D02*
X402330Y9270D01*
Y12412D01*
G01X418750Y30700D02*
Y34571D01*
X418705Y34616D01*
Y34695D01*
G01X409026Y61211D02*
X409781Y61966D01*
X415019D01*
G01X416300Y37100D02*
X415950D01*
X412250Y33400D01*
G01X363638Y31049D02*
Y31938D01*
X365650Y33950D01*
Y35400D01*
G01X402330Y28592D02*
Y34130D01*
X404500Y36300D01*
G01X408750Y33400D02*
X405850Y36300D01*
X404500D01*
G01X404911Y51269D02*
X405411Y51769D01*
X408933D01*
X411255Y54091D01*
X415019D01*
G01X426219Y44860D02*
Y38874D01*
X426919Y38174D01*
G01X414719Y63934D02*
X411866D01*
X410800Y65000D01*
X408512D01*
X407905Y65607D01*
G01X426219Y67260D02*
Y72566D01*
X426093Y72692D01*
Y75133D01*
X431900Y80940D01*
Y84079D01*
G01X431382Y35283D02*
X431600Y35065D01*
Y32322D01*
X429915Y30637D01*
G01X454500Y29300D02*
Y32000D01*
X453187Y33313D01*
X451070D01*
G01X450450Y44300D02*
X446400D01*
X440546Y50154D01*
X437419D01*
G01X437719Y63934D02*
Y65926D01*
X445485Y73692D01*
X447087D01*
X447438Y74043D01*
G01X431900Y84079D02*
X431684Y84295D01*
G01X521600Y162348D02*
Y158400D01*
G01X530160Y162448D02*
Y159660D01*
X529000Y158500D01*
G01X517530Y162352D02*
Y157470D01*
X520500Y154500D01*
G01X526110Y162452D02*
Y159110D01*
X525000Y158000D01*
G01X522904Y187808D02*
Y189904D01*
X525000Y192000D01*
Y195650D01*
X524350Y196300D01*
G01X520936Y187808D02*
Y191100D01*
G01X524873Y187808D02*
X525808D01*
X528998Y190998D01*
Y195152D01*
X527850Y196300D01*
G54D18*
X103300Y14400D03*
X107600D03*
X95700Y168900D03*
X71726Y155766D03*
X75804Y155748D03*
X83300Y158500D03*
X67500Y154200D03*
X63400D03*
X105218Y141258D03*
X75500Y207000D03*
X79500D03*
X91700D03*
X87500D03*
X116000Y14500D03*
X111800D03*
X156300Y15200D03*
X157000Y70800D03*
X137000Y52900D03*
X175320Y173098D03*
X171290D03*
X171300Y186200D03*
X234300Y175700D03*
X327800Y35900D03*
X331500Y28200D03*
X332100Y36000D03*
X345700Y76900D03*
X336300Y35900D03*
X307000Y182200D03*
X413800Y11800D03*
X375600Y78300D03*
X422638Y80676D03*
X418444Y80647D03*
X426696Y80704D03*
X414283Y80676D03*
X371500Y78300D03*
X395148Y69558D03*
X399318D03*
X439418Y29635D03*
X530160Y162498D03*
X521600Y162398D03*
X534348Y162458D03*
X516810Y202098D03*
X512680D03*
G54D36*
X102900Y52600D03*
X71200Y163800D03*
X98089Y135908D03*
X98085Y140036D03*
X105650Y164312D03*
Y168512D03*
X101072Y148907D03*
X101043Y153241D03*
X59700Y168300D03*
X121198Y89357D03*
X128000Y51900D03*
Y47700D03*
Y43500D03*
X115800Y74800D03*
X160300Y66400D03*
X121302Y98010D03*
X168154Y198330D03*
X246400Y180600D03*
Y176500D03*
X246600Y193200D03*
X210500Y195800D03*
X246600Y189000D03*
X237600Y198500D03*
X330400Y19700D03*
X336200Y52200D03*
X334100Y64700D03*
X337800Y69600D03*
X286800Y168400D03*
X305511Y198009D03*
X305400Y193700D03*
Y189700D03*
X296800Y187800D03*
X377087Y17368D03*
X387100Y13200D03*
X387200Y3300D03*
X376900Y7400D03*
X377100Y21500D03*
X390300Y69500D03*
X390200Y59600D03*
X380000Y65400D03*
X380213Y55568D03*
X390200Y46600D03*
X380200Y50700D03*
X380100Y38400D03*
X387100Y25800D03*
X453794Y52538D03*
X453806Y48469D03*
X451660Y66541D03*
X458000Y37100D03*
X429865Y30637D03*
X429800Y26500D03*
X544602Y176160D03*
Y172130D03*
G54D27*
X90700Y97100D03*
X65300Y143300D03*
X167500Y186000D03*
X192000Y177900D03*
X404330Y818D03*
X426919Y34624D03*
G54D45*
X75300Y163800D03*
X94676Y131798D03*
X95955Y144059D03*
X55900Y176800D03*
X56298Y172400D03*
X117820Y93564D03*
X121800Y74600D03*
X108365Y105330D03*
X109205Y109777D03*
X180100Y118500D03*
X172326Y198299D03*
X194013Y116998D03*
X241400Y117600D03*
X226698Y171220D03*
Y175550D03*
X226634Y195198D03*
X243198Y197300D03*
X234200Y194400D03*
X246400Y184900D03*
X327000Y23900D03*
X332800Y56300D03*
Y60400D03*
X306500Y116400D03*
X293400Y167600D03*
Y171800D03*
X373300Y-1200D03*
X373500Y3300D03*
X373683Y13318D03*
X383700Y17300D03*
X383800Y7400D03*
X360200Y-1800D03*
X373700Y25600D03*
X376600Y69500D03*
X418800Y30700D03*
X386800Y55500D03*
X418700Y26400D03*
X378400Y34200D03*
Y30100D03*
X386900Y65400D03*
X376817Y59618D03*
X386800Y50700D03*
X376800Y46600D03*
Y42500D03*
X383700Y21700D03*
X447528Y29487D03*
G54D54*
X122403Y148109D03*
X126338Y155984D03*
X130278Y148109D03*
X134213Y155984D03*
X138148Y148109D03*
X142088Y155984D03*
X146023Y148109D03*
X149963Y155984D03*
X153898Y148109D03*
X157833Y155984D03*
X161773Y148109D03*
X173583Y155984D03*
X177518Y148109D03*
X181458Y155984D03*
X185393Y148109D03*
X189333Y155984D03*
X122403Y138269D03*
X126338Y130394D03*
X130278Y138269D03*
X134213Y130394D03*
X138148Y138269D03*
X142088Y130394D03*
X146023Y138269D03*
X149963Y130394D03*
X153898Y138269D03*
X157833Y130394D03*
X161773Y138269D03*
X173583Y130394D03*
X177518Y138269D03*
X181458Y130394D03*
X185393Y138269D03*
X189333Y130394D03*
X122403Y228109D03*
X126338Y235984D03*
X130278Y228109D03*
X134213Y235984D03*
X138148Y228109D03*
X142088Y235984D03*
X146023Y228109D03*
X149963Y235984D03*
X153898Y228109D03*
X157833Y235984D03*
X161773Y228109D03*
X173583Y235984D03*
X177518Y228109D03*
X181458Y235984D03*
X185393Y228109D03*
X189333Y235984D03*
X122403Y218269D03*
X126338Y210394D03*
X130278Y218269D03*
X134213Y210394D03*
X138148Y218269D03*
X142088Y210394D03*
X146023Y218269D03*
X149963Y210394D03*
X153898Y218269D03*
X157833Y210394D03*
X161773Y218269D03*
X173583Y210394D03*
X177518Y218269D03*
X181458Y210394D03*
X185393Y218269D03*
X189333Y210394D03*
X193268Y148109D03*
X197203Y155984D03*
X201143Y148109D03*
X205078Y155984D03*
X209018Y148109D03*
X212953Y155984D03*
X216888Y148109D03*
X220828Y155984D03*
X224763Y148109D03*
X228703Y155984D03*
X232638Y148109D03*
X236573Y155984D03*
X240513Y148109D03*
X244448Y155984D03*
X248388Y148109D03*
X252323Y155984D03*
X256258Y148109D03*
X260198Y155984D03*
X264133Y148109D03*
X268073Y155984D03*
X193268Y138269D03*
X197203Y130394D03*
X201143Y138269D03*
X205078Y130394D03*
X209018Y138269D03*
X212953Y130394D03*
X216888Y138269D03*
X220828Y130394D03*
X224763Y138269D03*
X228703Y130394D03*
X232638Y138269D03*
X236573Y130394D03*
X240513Y138269D03*
X244448Y130394D03*
X248388Y138269D03*
X252323Y130394D03*
X256258Y138269D03*
X260198Y130394D03*
X264133Y138269D03*
X268073Y130394D03*
X193268Y228109D03*
X197203Y235984D03*
X201143Y228109D03*
X205078Y235984D03*
X209018Y228109D03*
X212953Y235984D03*
X216888Y228109D03*
X220828Y235984D03*
X224763Y228109D03*
X228703Y235984D03*
X232638Y228109D03*
X236573Y235984D03*
X240513Y228109D03*
X244448Y235984D03*
X248388Y228109D03*
X252323Y235984D03*
X256258Y228109D03*
X260198Y235984D03*
X264133Y228109D03*
X268073Y235984D03*
X193268Y218269D03*
X197203Y210394D03*
X201143Y218269D03*
X205078Y210394D03*
X209018Y218269D03*
X212953Y210394D03*
X216888Y218269D03*
X220828Y210394D03*
X224763Y218269D03*
X228703Y210394D03*
X232638Y218269D03*
X236573Y210394D03*
X240513Y218269D03*
X244448Y210394D03*
X248388Y218269D03*
X252323Y210394D03*
X256258Y218269D03*
X260198Y210394D03*
X264133Y218269D03*
X268073Y210394D03*
X272008Y148109D03*
X275943Y155984D03*
X279883Y148109D03*
X283818Y155984D03*
X287758Y148109D03*
X291693Y155984D03*
X295628Y148109D03*
X299568Y155984D03*
X303503Y148109D03*
X307443Y155984D03*
X311378Y148109D03*
X315313Y155984D03*
X319253Y148109D03*
X323188Y155984D03*
X327128Y148109D03*
X331063Y155984D03*
X334998Y148109D03*
X338938Y155984D03*
X342873Y148109D03*
X346813Y155984D03*
X272008Y138269D03*
X275943Y130394D03*
X279883Y138269D03*
X283818Y130394D03*
X287758Y138269D03*
X291693Y130394D03*
X295628Y138269D03*
X299568Y130394D03*
X303503Y138269D03*
X307443Y130394D03*
X311378Y138269D03*
X315313Y130394D03*
X319253Y138269D03*
X323188Y130394D03*
X327128Y138269D03*
X331063Y130394D03*
X334998Y138269D03*
X338938Y130394D03*
X342873Y138269D03*
X346813Y130394D03*
X272008Y228109D03*
X275943Y235984D03*
X279883Y228109D03*
X283818Y235984D03*
X287758Y228109D03*
X291693Y235984D03*
X295628Y228109D03*
X299568Y235984D03*
X303503Y228109D03*
X307443Y235984D03*
X311378Y228109D03*
X315313Y235984D03*
X319253Y228109D03*
X323188Y235984D03*
X327128Y228109D03*
X331063Y235984D03*
X334998Y228109D03*
X338938Y235984D03*
X342873Y228109D03*
X346813Y235984D03*
X272008Y218269D03*
X275943Y210394D03*
X279883Y218269D03*
X283818Y210394D03*
X287758Y218269D03*
X291693Y210394D03*
X295628Y218269D03*
X299568Y210394D03*
X303503Y218269D03*
X307443Y210394D03*
X311378Y218269D03*
X315313Y210394D03*
X319253Y218269D03*
X323188Y210394D03*
X327128Y218269D03*
X331063Y210394D03*
X334998Y218269D03*
X338938Y210394D03*
X342873Y218269D03*
X346813Y210394D03*
X350748Y148109D03*
X354683Y155984D03*
X358623Y148109D03*
X362558Y155984D03*
X366498Y148109D03*
X370433Y155984D03*
X374368Y148109D03*
X378308Y155984D03*
X382243Y148109D03*
X386183Y155984D03*
X390118Y148109D03*
X394053Y155984D03*
X397993Y148109D03*
X401928Y155984D03*
X405868Y148109D03*
X409803Y155984D03*
X413738Y148109D03*
X417678Y155984D03*
X421613Y148109D03*
X425553Y155984D03*
X429488Y148109D03*
X350748Y138269D03*
X354683Y130394D03*
X358623Y138269D03*
X362558Y130394D03*
X366498Y138269D03*
X370433Y130394D03*
X374368Y138269D03*
X378308Y130394D03*
X382243Y138269D03*
X386183Y130394D03*
X390118Y138269D03*
X394053Y130394D03*
X397993Y138269D03*
X401928Y130394D03*
X405868Y138269D03*
X409803Y130394D03*
X413738Y138269D03*
X417678Y130394D03*
X421613Y138269D03*
X425553Y130394D03*
X429488Y138269D03*
X350748Y228109D03*
X354683Y235984D03*
X358623Y228109D03*
X362558Y235984D03*
X366498Y228109D03*
X370433Y235984D03*
X374368Y228109D03*
X378308Y235984D03*
X382243Y228109D03*
X386183Y235984D03*
X390118Y228109D03*
X394053Y235984D03*
X397993Y228109D03*
X401928Y235984D03*
X405868Y228109D03*
X409803Y235984D03*
X413738Y228109D03*
X417678Y235984D03*
X421613Y228109D03*
X425553Y235984D03*
X429488Y228109D03*
X350748Y218269D03*
X354683Y210394D03*
X358623Y218269D03*
X362558Y210394D03*
X366498Y218269D03*
X370433Y210394D03*
X374368Y218269D03*
X378308Y210394D03*
X382243Y218269D03*
X386183Y210394D03*
X390118Y218269D03*
X394053Y210394D03*
X397993Y218269D03*
X401928Y210394D03*
X405868Y218269D03*
X409803Y210394D03*
X413738Y218269D03*
X417678Y210394D03*
X421613Y218269D03*
X425553Y210394D03*
X429488Y218269D03*
X433423Y155984D03*
X437363Y148109D03*
X441298Y155984D03*
X445238Y148109D03*
X449173Y155984D03*
X433423Y130394D03*
X437363Y138269D03*
X441298Y130394D03*
X445238Y138269D03*
X449173Y130394D03*
X433423Y235984D03*
X437363Y228109D03*
X441298Y235984D03*
X445238Y228109D03*
X449173Y235984D03*
X433423Y210394D03*
X437363Y218269D03*
X441298Y210394D03*
X445238Y218269D03*
X449173Y210394D03*
G54D63*
X410970Y37500D03*
X407357Y45482D03*
X404023Y61327D03*
X406449Y40438D03*
X448600Y109400D03*
X471500Y209500D03*
G54D73*
G01X56248Y172400D02*
Y176402D01*
X55850Y176800D01*
G01X65300Y146850D02*
X70535D01*
X73073Y144312D01*
Y143240D01*
G01X59600Y201500D02*
X65256Y195844D01*
X66197D01*
G01X262400Y169900D02*
X261100D01*
X259944Y171056D01*
Y173463D01*
G01X205780Y172408D02*
Y168580D01*
X202300Y165100D01*
G01X244850Y117600D02*
Y114450D01*
X246800Y112500D01*
G01X192000Y181450D02*
X194650Y184100D01*
Y187550D01*
X195688Y188588D01*
X198100D01*
G01X289050Y196800D02*
G02X285400Y196503I-3650J22280D01*
G01X282144D01*
G01X394650Y28592D02*
X392408D01*
X391600Y29400D01*
G01X366838Y68049D02*
Y72412D01*
X366750Y72500D01*
G54D19*
X103300Y17800D03*
X107600D03*
X95700Y172300D03*
X71726Y159166D03*
X75804Y159148D03*
X83300Y161900D03*
X67500Y157600D03*
X63400D03*
X105218Y144658D03*
X75500Y210400D03*
X79500D03*
X91700D03*
X87500D03*
X116000Y17900D03*
X111800D03*
X156300Y18600D03*
X157000Y74200D03*
X137000Y56300D03*
X175320Y176498D03*
X171290D03*
X171300Y189600D03*
X234300Y179100D03*
X327800Y39300D03*
X331500Y31600D03*
X332100Y39400D03*
X345700Y80300D03*
X336300Y39300D03*
X307000Y185600D03*
X413800Y15200D03*
X375600Y81700D03*
X422638Y84076D03*
X418444Y84047D03*
X426696Y84104D03*
X414283Y84076D03*
X371500Y81700D03*
X395148Y72958D03*
X399318D03*
X439418Y33035D03*
X530160Y165898D03*
X521600Y165798D03*
X534348Y165858D03*
X516810Y205498D03*
X512680D03*
G54D28*
X50813Y89796D03*
X51465Y146761D03*
G54D37*
X99500Y52600D03*
X67800Y163800D03*
X94689Y135908D03*
X94685Y140036D03*
X102250Y164312D03*
Y168512D03*
X97672Y148907D03*
X97643Y153241D03*
X56300Y168300D03*
X117798Y89357D03*
X124600Y51900D03*
Y47700D03*
Y43500D03*
X112400Y74800D03*
X156900Y66400D03*
X117902Y98010D03*
X164754Y198330D03*
X243000Y180600D03*
Y176500D03*
X243200Y193200D03*
X207100Y195800D03*
X243200Y189000D03*
X234200Y198500D03*
X327000Y19700D03*
X332800Y52200D03*
X330700Y64700D03*
X334400Y69600D03*
X283400Y168400D03*
X302111Y198009D03*
X302000Y193700D03*
Y189700D03*
X293400Y187800D03*
X373687Y17368D03*
X383700Y13200D03*
X383800Y3300D03*
X373500Y7400D03*
X373700Y21500D03*
X426465Y30637D03*
X426400Y26500D03*
X386900Y69500D03*
X386800Y59600D03*
X376600Y65400D03*
X376813Y55568D03*
X386800Y46600D03*
X376800Y50700D03*
X376700Y38400D03*
X383700Y25800D03*
X450394Y52538D03*
X450406Y48469D03*
X448260Y66541D03*
X454600Y37100D03*
X541202Y176160D03*
Y172130D03*
G54D55*
X165800Y103800D03*
G54D64*
X428027Y88710D03*
X445795Y78376D03*
G54D46*
X78700Y163800D03*
X98076Y131798D03*
X99355Y144059D03*
X59300Y176800D03*
X59698Y172400D03*
X121220Y93564D03*
X125200Y74600D03*
X111765Y105330D03*
X112605Y109777D03*
X183500Y118500D03*
X175726Y198299D03*
X197413Y116998D03*
X244800Y117600D03*
X230098Y171220D03*
Y175550D03*
X230034Y195198D03*
X246598Y197300D03*
X237600Y194400D03*
X249800Y184900D03*
X330400Y23900D03*
X336200Y56300D03*
Y60400D03*
X309900Y116400D03*
X296800Y167600D03*
Y171800D03*
X376700Y-1200D03*
X376900Y3300D03*
X377083Y13318D03*
X387100Y17300D03*
X387200Y7400D03*
X363600Y-1800D03*
X377100Y25600D03*
X380000Y69500D03*
X422200Y30700D03*
X390200Y55500D03*
X422100Y26400D03*
X381800Y34200D03*
Y30100D03*
X390300Y65400D03*
X380217Y59618D03*
X390200Y50700D03*
X380200Y46600D03*
Y42500D03*
X387100Y21700D03*
X450928Y29487D03*
G54D74*
G01X82100Y95600D02*
X86500Y91200D01*
X88050D01*
G01X91550D02*
Y92350D01*
X89400Y94500D01*
X87900D01*
G01X108040Y65950D02*
X102600D01*
X102500Y65850D01*
G01X90700Y100650D02*
X87250D01*
G01X113160Y59450D02*
X116900D01*
G01X120340Y65750D02*
X117200D01*
G01X133100Y56250D02*
X130650D01*
X127650Y59250D01*
X125460D01*
G01X192000Y177950D02*
X196850D01*
G01X197463Y116998D02*
Y112537D01*
X198300Y111700D01*
G01X324600Y36900D02*
X324350Y36650D01*
Y20350D01*
X325000Y19700D01*
X326950D01*
G01X328000Y59000D02*
X328600D01*
X330000Y60400D01*
X332750D01*
G01X326950Y23900D02*
Y29450D01*
X328000Y30500D01*
G01X332750Y56300D02*
Y60400D01*
G01X331500Y28150D02*
X330350D01*
X328000Y30500D01*
G01X329400Y50300D02*
Y50400D01*
X331200Y52200D01*
X332750D01*
G01X327800Y39350D02*
X328000Y39150D01*
X331800D01*
X332100Y39450D01*
G01X309950Y116400D02*
X312650Y119100D01*
X313400D01*
G01X380050Y69500D02*
X383200D01*
X383500Y69200D01*
G01X413800Y22750D02*
Y28100D01*
X412000Y29900D01*
G54D29*
X53357Y92340D03*
X54009Y149305D03*
G54D38*
X101722Y86658D03*
X103691D03*
X105659D03*
Y98870D03*
X103691D03*
X101722D03*
X76226Y134181D03*
X78195D03*
X80163D03*
X82132D03*
Y146393D03*
X80163D03*
X78195D03*
X76226D03*
X107628Y86658D03*
Y98870D03*
G54D47*
X66197Y173644D03*
X68757D03*
X71317D03*
X73877D03*
X76437D03*
X78997D03*
X81557D03*
X84117D03*
X86677D03*
X89237D03*
Y195844D03*
X86677D03*
X84117D03*
X81557D03*
X78997D03*
X76437D03*
X73877D03*
X71317D03*
X68757D03*
X66197D03*
X205780Y172408D03*
X203220D03*
X200660D03*
X198100D03*
Y188588D03*
X200660D03*
X203220D03*
X205780D03*
X402330Y12412D03*
X399770D03*
X397210D03*
X394650D03*
Y28592D03*
X397210D03*
X399770D03*
X402330D03*
G54D65*
X444705Y-64309D03*
X447854D03*
X451004D03*
X454154D03*
X457303D03*
X460453D03*
X463602D03*
X466752D03*
X469902D03*
X473051D03*
X476201D03*
X479350D03*
X482500D03*
X485650D03*
X488799D03*
X491949D03*
X495098D03*
X498248D03*
X501398D03*
X504547D03*
X507697D03*
X510846D03*
X513996D03*
X517146D03*
X520295D03*
X523445D03*
X526594D03*
X529744D03*
X532894D03*
X536043D03*
G54D56*
X171400Y103800D03*
G54D75*
G01X103300Y17850D02*
X99450D01*
X99200Y18100D01*
G01X98300Y72000D02*
X99100D01*
X101750Y69350D01*
X102500D01*
G01X116000Y17950D02*
X120249D01*
X121200Y16999D01*
X121801D01*
G01X160650Y62300D02*
Y66100D01*
X160350Y66400D01*
G01D02*
Y69650D01*
X161800Y71100D01*
G01X133100Y59750D02*
Y62500D01*
X134000Y63400D01*
G01X324600Y36900D02*
X327050Y39350D01*
X327800D01*
G01X334350Y69600D02*
Y71350D01*
X336300Y73300D01*
X339100D01*
G01X334350Y69600D02*
X330650Y65900D01*
Y64700D01*
G01X383650Y17300D02*
X380700D01*
X380500Y17100D01*
G01X376950Y7400D02*
X379300D01*
X379900Y6800D01*
X380200D01*
G01D02*
X380900D01*
X381500Y7400D01*
X383750D01*
G01X377137Y17368D02*
X380232D01*
X380500Y17100D01*
G01X383650Y13200D02*
X380500D01*
G01X377133Y13318D02*
X380382D01*
X380500Y13200D01*
G01X376950Y3300D02*
Y-1000D01*
X376750Y-1200D01*
G01X383750Y3300D02*
X380200D01*
G01D02*
X376950D01*
G01X380250Y50700D02*
X383300D01*
G01X386850Y65400D02*
X383900D01*
X383500Y65800D01*
G01X377150Y21500D02*
X380200D01*
X380300Y21600D01*
G01X383650Y21700D02*
X380400D01*
X380300Y21600D01*
G01X369150Y35400D02*
X373300D01*
G01X380050Y65400D02*
X383100D01*
X383500Y65800D01*
G01X386750Y55500D02*
X383632D01*
X383600Y55532D01*
G01X380263Y55568D02*
X383564D01*
X383600Y55532D01*
G01X386750Y50700D02*
X383300D01*
G01X363250Y72500D02*
Y70750D01*
X361600Y69100D01*
G01X384000Y41600D02*
Y41100D01*
X381300Y38400D01*
X380150D01*
G01X386850Y69500D02*
X383800D01*
X383500Y69200D01*
G01X380267Y59618D02*
X383600D01*
G01X386750Y59600D02*
X383618D01*
X383600Y59618D01*
G01X380250Y42500D02*
Y46600D01*
G01D02*
X383400D01*
G01X365650Y35400D02*
X363300D01*
X362400Y34500D01*
G01X383650Y25800D02*
X380200D01*
G01X377150Y25600D02*
X380000D01*
X380200Y25800D01*
G01X383400Y46600D02*
X383500Y46500D01*
X386650D01*
X386750Y46600D01*
G01X450400Y40550D02*
X453950D01*
X454000Y40600D01*
G54D39*
X98569Y95717D03*
Y93748D03*
Y91780D03*
Y89811D03*
X73073Y143240D03*
Y141271D03*
Y139303D03*
Y137334D03*
X85285D03*
Y139303D03*
Y141271D03*
Y143240D03*
X110781Y89811D03*
Y91780D03*
Y93748D03*
Y95717D03*
G54D57*
X259944Y178583D03*
Y176023D03*
Y173463D03*
Y196503D03*
Y193943D03*
Y191383D03*
Y188823D03*
Y186263D03*
Y183703D03*
Y181143D03*
X341438Y2889D03*
Y5449D03*
Y8009D03*
Y10569D03*
Y13129D03*
Y15689D03*
Y18249D03*
Y20809D03*
Y23369D03*
Y25929D03*
Y28489D03*
Y31049D03*
X344638Y39889D03*
Y42449D03*
Y45009D03*
Y47569D03*
Y50129D03*
Y52689D03*
Y55249D03*
Y57809D03*
Y60369D03*
Y62929D03*
Y65489D03*
Y68049D03*
X282144Y173463D03*
Y176023D03*
Y178583D03*
Y181143D03*
Y183703D03*
Y186263D03*
Y188823D03*
Y191383D03*
Y193943D03*
Y196503D03*
X363638Y18249D03*
Y15689D03*
Y13129D03*
Y10569D03*
Y8009D03*
Y5449D03*
Y2889D03*
Y31049D03*
Y28489D03*
Y25929D03*
Y23369D03*
Y20809D03*
X366838Y68049D03*
Y65489D03*
Y62929D03*
Y60369D03*
Y57809D03*
Y55249D03*
Y52689D03*
Y50129D03*
Y47569D03*
Y45009D03*
Y42449D03*
Y39889D03*
G54D66*
X433627Y88710D03*
X451395Y78376D03*
G54D48*
X40794Y230682D03*
X37095Y524125D03*
X540347Y32747D03*
X572386Y532294D03*
X601314Y-26920D03*
X599868Y229462D03*
G54D76*
G01X103300Y14350D02*
X103525Y14125D01*
Y9575D01*
X101502Y7552D01*
Y-49702D01*
X103100Y-51300D01*
Y-55900D01*
X105355Y-58155D01*
Y-63909D01*
G01X102205D02*
Y-58220D01*
X100955Y-56970D01*
Y-51455D01*
X99400Y-49900D01*
Y4800D01*
X97300Y6900D01*
Y9100D01*
X98200Y10000D01*
G01X94042Y9842D02*
X95400Y8484D01*
Y5700D01*
X97500Y3600D01*
Y-50688D01*
X99055Y-52243D01*
Y-63909D01*
G01X107600Y14350D02*
X103300D01*
G01X98700Y60750D02*
X101850D01*
X102800Y61700D01*
G01D02*
X103200D01*
X105450Y59450D01*
X108040D01*
G01X104500Y56200D02*
X99750D01*
X98700Y57250D01*
G01X83200Y60000D02*
X83400Y60200D01*
X91850D01*
X99450Y52600D01*
G01X108800Y49150D02*
X106400D01*
X102950Y52600D01*
G01X95700Y176350D02*
X99350D01*
X100000Y175700D01*
G01X109155Y109777D02*
X106800Y109500D01*
X105500D01*
G01X94635Y140036D02*
X93902Y139303D01*
X91241D01*
X90972Y139034D01*
G01X95905Y144059D02*
Y142705D01*
X94605Y141405D01*
Y140066D01*
X94635Y140036D01*
G01X90972Y139034D02*
X90703Y139303D01*
X85285D01*
G01X94639Y135908D02*
Y131811D01*
X94626Y131798D01*
G01X91004Y134234D02*
X91000Y134238D01*
Y134700D01*
X88366Y137334D01*
X85285D01*
G01X94639Y135908D02*
X92965Y134234D01*
X91004D01*
G01X97593Y153241D02*
X90641D01*
X89700Y152300D01*
G01D02*
X83793Y146393D01*
X82132D01*
G01X93700Y149200D02*
X91388D01*
X88288Y146100D01*
X86337D01*
X85285Y145048D01*
Y143240D01*
G01X93700Y149200D02*
X93993Y148907D01*
X97622D01*
G01X66197Y173644D02*
X62506D01*
X59350Y176800D01*
G01X60400Y187700D02*
X60700Y187400D01*
Y178150D01*
X59350Y176800D01*
G01X59750Y168300D02*
X63400D01*
G01X59748Y172400D02*
Y168302D01*
X59750Y168300D01*
G01X68757Y173644D02*
Y170157D01*
X67400Y168800D01*
X63900D01*
X63400Y168300D01*
G01Y157650D02*
X62500Y158550D01*
Y161700D01*
G01X63400Y157650D02*
X59400D01*
X59300Y157750D01*
G01X71317Y173644D02*
Y170863D01*
X69700Y169246D01*
Y169200D01*
X67800Y167300D01*
X66300D01*
X62500Y163500D01*
Y161700D01*
G01X105400Y153600D02*
X103876Y152076D01*
X102258D01*
X101093Y153241D01*
G01X78997Y173644D02*
Y169616D01*
X76897Y167516D01*
X76613D01*
G01X75250Y163800D02*
X74800Y163350D01*
Y160202D01*
X75804Y159198D01*
G01X76613Y167516D02*
Y167232D01*
X75250Y165869D01*
Y163800D01*
G01X88400Y158500D02*
X96600D01*
X98873Y160773D01*
X113327D01*
X115000Y159100D01*
Y157900D01*
X116176Y156724D01*
G01X88400Y158500D02*
X86512D01*
X80112Y152100D01*
X75788D01*
X74900Y152988D01*
Y154794D01*
X75804Y155698D01*
G01X95700Y168850D02*
X96550Y168000D01*
X101688D01*
X102200Y168512D01*
G01X95700Y168850D02*
X94350Y167500D01*
X89700D01*
X89500Y167700D01*
G01X86677Y173644D02*
Y170223D01*
X89200Y167700D01*
X89500D01*
G01X105700Y168512D02*
X106712Y167500D01*
X108248D01*
X109500Y168752D01*
G01X106500Y149000D02*
X105324Y150176D01*
X102391D01*
X101122Y148907D01*
G01X71250Y163800D02*
X72000Y164550D01*
Y165949D01*
X73906Y167855D01*
Y167906D01*
X74413Y168413D01*
Y168428D01*
X75701Y169716D01*
X75716D01*
X76437Y170437D01*
Y173644D01*
G01X70800Y152000D02*
X69900Y152900D01*
Y157390D01*
X71726Y159216D01*
G01X71250Y163800D02*
X72900Y162150D01*
Y160390D01*
X71726Y159216D01*
G01Y155716D02*
X73000Y154442D01*
Y152200D01*
X75000Y150200D01*
X80900D01*
X86050Y155350D01*
X92550D01*
X93200Y156000D01*
G01X111924Y156724D02*
X113100Y157900D01*
Y158312D01*
X112539Y158873D01*
X99661D01*
X97038Y156250D01*
X93450D01*
X93200Y156000D01*
G01X84117Y173644D02*
Y169771D01*
X85200Y168688D01*
Y165000D01*
X86772Y163428D01*
X87309D01*
G01X95700Y164850D02*
X96850Y166000D01*
X100512D01*
X102200Y164312D01*
G01X87309Y163428D02*
X88628D01*
X90800Y165600D01*
X94950D01*
X95700Y164850D01*
G01X109500Y164500D02*
X109445D01*
X108445Y165500D01*
X106888D01*
X105700Y164312D01*
G01X92100Y143700D02*
Y143800D01*
X94700Y146400D01*
X103526D01*
X105218Y144708D01*
G01X92100Y143700D02*
X89200D01*
X86771Y141271D01*
X85285D01*
G01X105218Y141208D02*
Y137218D01*
G01X67500Y157650D02*
X65200Y159950D01*
Y164156D01*
X67144Y166100D01*
X69100D01*
X71500Y168500D01*
G01X73877Y173644D02*
Y170877D01*
X71500Y168500D01*
G01X83300Y161950D02*
Y167900D01*
X81557Y169643D01*
Y173644D01*
G01X96000Y192000D02*
X81557Y177557D01*
Y173644D01*
G01X106178Y223167D02*
X107567D01*
X112509Y228109D01*
X122403D01*
G01X84400Y202800D02*
Y203850D01*
X87500Y206950D01*
G01X84117Y195844D02*
Y202517D01*
X84400Y202800D01*
G01X86677Y195844D02*
Y199565D01*
X89944Y202832D01*
G01D02*
X91700Y204588D01*
Y206950D01*
G01X95900D02*
Y199600D01*
X94900Y198600D01*
G01X89237Y195844D02*
X92144D01*
X94900Y198600D01*
G01X55900Y210450D02*
X53900Y208450D01*
Y201400D01*
X60400Y194900D01*
Y187700D01*
G01X75500Y206950D02*
Y202767D01*
X75591Y202676D01*
G01D02*
X76437Y201830D01*
Y195844D01*
G01X67400Y206950D02*
Y204000D01*
X68200Y203200D01*
G01D02*
X71317Y200083D01*
Y195844D01*
G01X79500Y206950D02*
X79843Y206607D01*
Y202676D01*
G01X78997Y195844D02*
Y201830D01*
X79843Y202676D01*
G01X63300Y203000D02*
Y202200D01*
X64700Y200800D01*
X67326D01*
X68757Y199369D01*
Y195844D01*
G01X63400Y206950D02*
Y203100D01*
X63300Y203000D01*
G01X83500Y206950D02*
X81900Y205350D01*
Y199900D01*
X81557Y199557D01*
Y195844D01*
G01D02*
Y190943D01*
X83500Y189000D01*
G01X73877Y195844D02*
Y200723D01*
X72200Y202400D01*
G01X71500Y206950D02*
Y203100D01*
X72200Y202400D01*
G01X67500Y213500D02*
X67383D01*
X66500Y212617D01*
Y211350D01*
X67400Y210450D01*
G01X64000Y213500D02*
X64500Y213000D01*
Y211550D01*
X63400Y210450D01*
G01X121103Y-63909D02*
Y-54697D01*
X145900Y-29900D01*
Y-27598D01*
X156908Y-16590D01*
Y-10001D01*
X164000Y-2909D01*
Y33400D01*
X169800Y39200D01*
G01X142000Y-30200D02*
Y-32000D01*
X119900Y-54100D01*
Y-56400D01*
X117953Y-58347D01*
Y-63909D01*
G01X160400Y4900D02*
X159100Y3600D01*
X154900D01*
X153148Y1848D01*
Y-42D01*
G01Y7358D02*
Y9048D01*
X156300Y12200D01*
Y15150D01*
G01X150588Y7358D02*
Y11888D01*
X151800Y13100D01*
G01X156300Y15150D02*
X153850D01*
X151800Y13100D01*
G01X155708Y-42D02*
Y-16092D01*
X142000Y-29800D01*
Y-30200D01*
G01X107600Y14350D02*
Y12100D01*
X107400Y11900D01*
Y11300D01*
G01X111800Y14450D02*
Y12164D01*
X111018Y11382D01*
G01X116000Y14450D02*
X111800D01*
G01X129400Y62200D02*
Y64300D01*
X127950Y65750D01*
X125460D01*
G01X108600Y73000D02*
Y72748D01*
X113160Y68188D01*
Y65950D01*
G01X112350Y74800D02*
X109500D01*
X108600Y73900D01*
Y73000D01*
G01X115850Y74800D02*
Y77498D01*
X117500Y79148D01*
G01X122900Y65750D02*
Y73450D01*
X121750Y74600D01*
G01D02*
Y76550D01*
X119152Y79148D01*
X117500D01*
G01X120340Y59250D02*
X119550Y58460D01*
Y48950D01*
X120000Y48500D01*
G01X124550Y51900D02*
Y47700D01*
G01Y43500D02*
Y47700D01*
G01D02*
X120800D01*
X120000Y48500D01*
G01X128050Y51900D02*
X129500D01*
X133800Y47600D01*
X142000D01*
X153000Y58600D01*
X161300D01*
X161400Y58700D01*
G01X154300Y56400D02*
Y54100D01*
X145600Y45400D01*
X130350D01*
X128050Y47700D01*
G01X151200Y62700D02*
Y66700D01*
X152300Y67800D01*
X152500D01*
G01X156850Y66400D02*
Y70600D01*
X157000Y70750D01*
G01X157150Y62300D02*
Y66100D01*
X156850Y66400D01*
G01X152500Y67800D02*
X155450Y70750D01*
X157000D01*
G01X125250Y74600D02*
Y77750D01*
X124100Y78900D01*
G01X137000Y52850D02*
Y50300D01*
X137900Y49400D01*
G01X142400Y58700D02*
Y58250D01*
X137000Y52850D01*
G01X117748Y89357D02*
X118120Y89729D01*
Y93280D01*
X117836Y93564D01*
X117770D01*
G01X110781Y91780D02*
X115986D01*
X117770Y93564D01*
G01X117748Y89357D02*
Y85396D01*
X117400Y85048D01*
G01X110781Y89811D02*
Y87200D01*
G01X107628Y98870D02*
X109482D01*
X113212Y102600D01*
X115200D01*
X116400Y103800D01*
G01X120998Y107721D02*
Y107712D01*
X120186Y106900D01*
Y104474D01*
X116012Y100300D01*
X113600D01*
X111750Y98450D01*
G01D02*
X110781Y97481D01*
Y95717D01*
G01X128050Y43500D02*
X149900D01*
X152900Y46500D01*
G01X110781Y93748D02*
X112948D01*
X114850Y95650D01*
G01D02*
X117210Y98010D01*
X117852D01*
G01X124400Y103100D02*
Y102900D01*
X121352Y99852D01*
Y98010D01*
G01X110600Y59450D02*
Y53700D01*
X109900Y53000D01*
G01X108800Y49150D02*
Y51900D01*
X109900Y53000D01*
G01X111815Y105330D02*
Y107117D01*
X109155Y109777D01*
G01X180050Y118500D02*
X179700Y118850D01*
Y120500D01*
X173583Y126617D01*
Y130394D01*
G01X181800Y110500D02*
Y116750D01*
X180050Y118500D01*
G01X116671Y107715D02*
Y104071D01*
X116400Y103800D01*
G01X117600Y117700D02*
Y116100D01*
X116671Y115171D01*
Y111215D01*
G01X185182Y170092D02*
Y174166D01*
X185126Y174222D01*
Y174949D01*
X185900Y175723D01*
Y182612D01*
X186688Y183400D01*
G01X175320Y176548D02*
X174444Y177424D01*
Y179944D01*
X175300Y180800D01*
X179152D01*
X180076Y179876D01*
G01X175320Y173048D02*
X174750Y172478D01*
Y167650D01*
X175600Y166800D01*
G01X121700Y117300D02*
Y116600D01*
X120995Y115895D01*
Y112855D01*
X120998Y111221D01*
G01X185712Y188700D02*
X184000Y186988D01*
Y176511D01*
X181152Y173663D01*
Y170092D01*
G01X171290Y176548D02*
Y177090D01*
X172000Y177800D01*
Y180188D01*
X174512Y182700D01*
X179200D01*
X180000Y183500D01*
G01X171290Y173048D02*
X172850Y171488D01*
Y167650D01*
X172000Y166800D01*
G01X181400Y124500D02*
Y120650D01*
X183550Y118500D01*
G01X171300Y186150D02*
X172450D01*
X175300Y189000D01*
X178500D01*
X180300Y187200D01*
G01X173583Y210394D02*
X171000Y207811D01*
Y199575D01*
X172276Y198299D01*
G01X179900Y191300D02*
X179600D01*
X174800Y196100D01*
X169082D01*
X168204Y196978D01*
Y198330D01*
G01X193268Y218269D02*
X188737Y222800D01*
X177500D01*
X168800Y214100D01*
Y198926D01*
X168204Y198330D01*
G01X186688Y183400D02*
X188600Y185312D01*
Y188900D01*
X193900Y194200D01*
X198701D01*
X200660Y192241D01*
Y188588D01*
G01X180000Y198500D02*
Y197835D01*
X180600Y197235D01*
Y196546D01*
X183023Y194123D01*
X187623D01*
X196400Y202900D01*
X211412D01*
X215100Y199212D01*
Y181400D01*
X223800Y172700D01*
X225168D01*
X226648Y171220D01*
G01X203220Y188588D02*
Y192369D01*
X199489Y196100D01*
X193112D01*
X185712Y188700D01*
G01X185788D02*
X185712D01*
G01X226648Y175550D02*
X225698Y174600D01*
X224588D01*
X217000Y182188D01*
Y200000D01*
X212200Y204800D01*
X195612D01*
X186835Y196023D01*
X183811D01*
X183092Y196742D01*
Y197926D01*
X183683Y198517D01*
G01X175776Y198299D02*
Y199324D01*
X173400Y201700D01*
Y204869D01*
G01D02*
X173300Y204969D01*
G01X259944Y181143D02*
X254975D01*
X247832Y174000D01*
X241100D01*
X239300Y175800D01*
Y178400D01*
X231900Y185800D01*
Y186046D01*
X230846Y187100D01*
X230600D01*
X229300Y188400D01*
X221500D01*
X218900Y191000D01*
Y200788D01*
X212988Y206700D01*
X194500D01*
X192400Y204600D01*
X175400D01*
X175131Y204869D01*
X173400D01*
G01X193963Y116998D02*
Y110137D01*
X199400Y104700D01*
Y98200D01*
X199500Y98100D01*
G01D02*
X199400Y98000D01*
Y81400D01*
G01X241350Y117600D02*
X236900Y113150D01*
Y85800D01*
G01X193268Y138269D02*
Y117693D01*
X193963Y116998D01*
G01X248388Y138269D02*
X248300Y138181D01*
Y128800D01*
X241350Y121850D01*
Y117600D01*
G01X282144Y191383D02*
X278491D01*
X278161Y191713D01*
X275101D01*
X274200Y190812D01*
Y173012D01*
X264788Y163600D01*
X220712D01*
X200990Y183322D01*
Y184605D01*
X200660Y184935D01*
Y188588D01*
G01X246450Y176500D02*
X248050Y178100D01*
X249244D01*
X255177Y184033D01*
X255961D01*
X256291Y183703D01*
X259944D01*
G01X251700Y171900D02*
X248800Y169000D01*
X240312D01*
X236956Y172356D01*
X235106D01*
X234200Y171450D01*
G01X230148Y171220D02*
X233970D01*
X234200Y171450D01*
G01X259944Y176023D02*
X255823D01*
X251700Y171900D01*
G01X203220Y188588D02*
Y184935D01*
X202890Y184605D01*
Y184110D01*
X221500Y165500D01*
X264000D01*
X272300Y173800D01*
Y191600D01*
X274313Y193613D01*
X278161D01*
X278491Y193943D01*
X282144D01*
G01X230148Y175550D02*
X234200D01*
X234300Y175650D01*
G01X242100Y171200D02*
X241100D01*
X238000Y174300D01*
X235650D01*
X234300Y175650D01*
G01X259944Y178583D02*
X256291D01*
X255961Y178253D01*
X254773D01*
X247420Y170900D01*
X242400D01*
X242100Y171200D01*
G01X199900Y161600D02*
X200500Y161000D01*
X265600D01*
X277000Y172400D01*
Y188000D01*
X277823Y188823D01*
X282144D01*
G01X192200Y166700D02*
X197812D01*
X200660Y169548D01*
Y172408D01*
G01X195900Y162100D02*
X203220Y169420D01*
Y172408D01*
G01X226584Y195198D02*
Y196445D01*
X231539Y201400D01*
X234200D01*
X240500Y207700D01*
Y211900D01*
X246869Y218269D01*
X248388D01*
G01X224100Y200100D02*
Y195800D01*
X224702Y195198D01*
X226584D01*
G01X237650Y198500D02*
Y200150D01*
X240700Y203200D01*
X247200D01*
X250700Y199700D01*
X256747D01*
G01X237650Y194400D02*
Y198500D01*
G01X259944Y196503D02*
X256747Y199700D01*
G01X259944Y193943D02*
X251543D01*
X250800Y193200D01*
X250300D01*
X250100Y193000D01*
G01X246650Y193200D02*
Y197298D01*
X246648Y197300D01*
G01X250100Y193000D02*
X249900Y193200D01*
X246650D01*
G01Y189000D02*
X248100D01*
X248300Y189200D01*
X250300D01*
X250400Y189100D01*
G01X246650Y189000D02*
Y188100D01*
X249850Y184900D01*
G01X259944Y191383D02*
X251583D01*
X250673Y190473D01*
Y189373D01*
X250400Y189100D01*
G01X211888Y189000D02*
Y190962D01*
X207050Y195800D01*
G01X205780Y188588D02*
X211476D01*
X211888Y189000D01*
G01X259944Y183703D02*
X264397D01*
X266100Y182000D01*
X267500D01*
G01X246450Y180600D02*
X247050Y180000D01*
X248456D01*
X254389Y185933D01*
X255961D01*
X256291Y186263D01*
X259944D01*
G01D02*
X264525D01*
X265688Y185100D01*
X266000D01*
G01X259944Y188823D02*
X255423D01*
X254900Y188300D01*
G01X355370Y37411D02*
X357100Y35681D01*
Y16400D01*
X346149Y5449D01*
X341438D01*
G01X349000Y28300D02*
X348900Y28200D01*
Y23000D01*
X344149Y18249D01*
X341438D01*
G01X330450Y19700D02*
Y23900D01*
G01X350300Y31800D02*
X350800Y31300D01*
Y22400D01*
X344089Y15689D01*
X341438D01*
G01X351500Y36100D02*
X352100Y35500D01*
Y21500D01*
X343729Y13129D01*
X341438D01*
G01X352700Y40000D02*
Y38700D01*
X353500Y37900D01*
Y18900D01*
X345169Y10569D01*
X341438D01*
G01X355300Y33900D02*
X354872Y33472D01*
Y18172D01*
X344709Y8009D01*
X341438D01*
G01X343524Y36971D02*
X343300Y36747D01*
Y34300D01*
X345500Y32100D01*
Y24900D01*
X343969Y23369D01*
X341438D01*
G01X344638Y60369D02*
X346869D01*
X349701Y63201D01*
Y64199D01*
G01X346000Y34640D02*
Y34600D01*
X346700Y33900D01*
Y23700D01*
X343809Y20809D01*
X341438D01*
G01X344638Y57809D02*
X347009D01*
X353100Y63900D01*
G01X359023Y47177D02*
X357931D01*
X353203Y42449D01*
X344638D01*
G01X349700Y56000D02*
X348949Y55249D01*
X344638D01*
G01X331500Y31650D02*
X334850D01*
X335100Y31400D01*
G01X327800Y35850D02*
Y35350D01*
X331500Y31650D01*
G01X335100Y31400D02*
Y31200D01*
X337811Y28489D01*
X341438D01*
G01X334700Y24369D02*
X336260Y25929D01*
X341438D01*
G01X330450Y23900D02*
X334231D01*
X334700Y24369D01*
G01X341438Y31049D02*
Y33962D01*
X339900Y35500D01*
Y35700D01*
G01X332100Y35950D02*
X336200D01*
X336300Y35850D01*
G01X339900Y35700D02*
X339600D01*
X339550Y35750D01*
X336400D01*
X336300Y35850D01*
G01X334150Y64700D02*
Y62500D01*
X336250Y60400D01*
G01X334150Y64700D02*
X337400D01*
X338100Y65400D01*
G01X344638Y65489D02*
X338189D01*
X338100Y65400D01*
G01X336250Y52200D02*
Y49750D01*
X334200Y47700D01*
G01X336250Y56300D02*
Y57250D01*
X341929Y62929D01*
X344638D01*
G01X336250Y52200D02*
Y56300D01*
G01X337850Y69600D02*
X338750Y70500D01*
X340000D01*
X342700Y73200D01*
X342900D01*
G01X345700Y76850D02*
Y76000D01*
X342900Y73200D01*
G01X344638Y68049D02*
X339401D01*
X337850Y69600D01*
G01X353098Y55882D02*
X349905Y52689D01*
X344638D01*
G01Y50129D02*
X351538D01*
X352138Y50729D01*
G01X355536Y50589D02*
X352647Y47700D01*
X350054D01*
X349923Y47569D01*
X344638D01*
G01Y45009D02*
X353209D01*
X355391Y47191D01*
X355399D01*
G01X336300Y39350D02*
Y45200D01*
X337900Y46800D01*
G01X345700Y80350D02*
Y84350D01*
X346150Y84800D01*
G01X300800Y100100D02*
X300465Y100435D01*
Y102396D01*
X303954Y113158D01*
X304100Y113600D01*
X306450Y115950D01*
Y116400D01*
G01X315313Y130394D02*
Y128876D01*
X306450Y120013D01*
Y116400D01*
G01X283350Y168400D02*
Y172257D01*
X282144Y173463D01*
G01X274400Y161700D02*
X281100Y168400D01*
X283350D01*
G01X293350Y171800D02*
Y172150D01*
X289000Y176500D01*
Y176600D01*
G01D02*
X288300Y177300D01*
X288200D01*
X286917Y178583D01*
X282144D01*
G01Y176023D02*
X284977D01*
X288200Y172800D01*
Y172750D01*
X289150Y171800D01*
X289600D01*
G01D02*
Y171350D01*
X293350Y167600D01*
G01X319700Y178200D02*
X316800Y181100D01*
X308050D01*
X307000Y182150D01*
G01X327200Y178276D02*
X326024Y177100D01*
X320800D01*
X319700Y178200D01*
G01X282144Y183703D02*
X285797D01*
X286127Y184033D01*
X286779D01*
X288012Y182800D01*
X293212D01*
X296812Y179200D01*
X305950D01*
X307000Y178150D01*
G01X327200Y174024D02*
X326024Y175200D01*
X317200D01*
X314000Y178400D01*
G01X307000Y178150D02*
X308050Y179200D01*
X313200D01*
X314000Y178400D01*
G01X301100Y171350D02*
X292581Y179869D01*
G01D02*
X291650Y180800D01*
X286400D01*
X286057Y181143D01*
X282144D01*
G01X301100Y171350D02*
X305850Y166600D01*
X344800D01*
X346400Y168200D01*
X346500D01*
X348200Y169900D01*
G01X305561Y198009D02*
X315313Y207761D01*
Y210394D01*
G01X334794Y195294D02*
X332079Y198009D01*
X305561D01*
G01X301950Y189700D02*
X300950Y190700D01*
X297600D01*
X296587Y191713D01*
X286127D01*
X285797Y191383D01*
X282144D01*
G01X301950Y193700D02*
X300850Y192600D01*
X298388D01*
X297375Y193613D01*
X286127D01*
X285797Y193943D01*
X282144D01*
G01Y188823D02*
X287977D01*
X289000Y187800D01*
X293350D01*
G01X282144Y186263D02*
X285797D01*
X286127Y185933D01*
X287567D01*
X288800Y184700D01*
X294000D01*
X297600Y181100D01*
X305950D01*
X307000Y182150D01*
G01X305450Y189700D02*
X308900D01*
X309500Y190300D01*
G01X321600Y186300D02*
X317150Y190750D01*
X309950D01*
X309500Y190300D01*
G01X305450Y193700D02*
X306500Y192650D01*
X319150D01*
X321700Y190100D01*
G01D02*
X323800Y188000D01*
Y183880D01*
X323243Y183323D01*
G01X411450Y-8329D02*
Y-29611D01*
X402182Y-38879D01*
X400421D01*
X399000Y-40300D01*
Y-45771D01*
X401615Y-48386D01*
Y-56244D01*
X401418Y-56441D01*
Y-63909D01*
G01X363650Y-1800D02*
Y2877D01*
X363638Y2889D01*
G01X363650Y-1800D02*
X368431D01*
X368700Y-1531D01*
G01X373250Y-1200D02*
X369031D01*
X368700Y-1531D01*
G01X373450Y7400D02*
Y3300D01*
G01X363638Y10569D02*
X366631D01*
X369900Y7300D01*
G01X373450Y7400D02*
X370000D01*
X369900Y7300D01*
G01X387250Y7400D02*
X384750Y9900D01*
X369400D01*
X368800Y10500D01*
X368788D01*
X367500Y11788D01*
Y11800D01*
X366171Y13129D01*
X363638D01*
G01X387250Y3300D02*
X389900D01*
X391100Y4500D01*
G01D02*
Y4900D01*
X388600Y7400D01*
X387250D01*
G01X387150Y13200D02*
Y17300D01*
G01X369700Y12700D02*
X371300Y11100D01*
X385050D01*
X387150Y13200D01*
G01X369700Y12700D02*
X369600D01*
X366611Y15689D01*
X363638D01*
G01X373633Y13318D02*
Y17364D01*
X373637Y17368D01*
G01D02*
X369610D01*
X369482Y17496D01*
G01X363638Y18249D02*
X368729D01*
X369482Y17496D01*
G01X363638Y20809D02*
X369281D01*
X370490Y19600D01*
X385050D01*
X387150Y21700D01*
G01X394650Y12412D02*
Y6350D01*
X396000Y5000D01*
G01D02*
X399950Y1050D01*
X400200D01*
G01X419450Y16771D02*
X419871D01*
X425200Y22100D01*
Y25250D01*
X426350Y26400D01*
Y26500D01*
G01X399770Y12412D02*
Y15570D01*
X400800Y16600D01*
X412450D01*
X413800Y15250D01*
G01D02*
X415450Y16900D01*
X419321D01*
X419450Y16771D01*
G01X397210Y12412D02*
Y16510D01*
X399200Y18500D01*
X409079D01*
X409550Y18971D01*
G01X413800Y19250D02*
X419650D01*
X423300Y22900D01*
Y25250D01*
X422150Y26400D01*
G01X413800Y19250D02*
X413350Y18800D01*
X409721D01*
X409550Y18971D01*
G01X411450Y-1048D02*
Y-8329D01*
G01X358700Y38100D02*
Y6549D01*
X359800Y5449D01*
X363638D01*
G01X362100Y38100D02*
Y37500D01*
X359938Y35338D01*
Y8471D01*
X360400Y8009D01*
X363638D01*
G01X416500Y76200D02*
X418444Y79044D01*
Y80597D01*
G01X420313Y67260D02*
Y72387D01*
X416500Y76200D01*
G01X409700Y77200D02*
X409706D01*
X413319Y73587D01*
X414983D01*
X418345Y70225D01*
Y67560D01*
G01X409700Y77200D02*
Y78500D01*
X411826Y80626D01*
X414283D01*
G01X410970Y37500D02*
X413350Y39880D01*
X419942D01*
X422282Y42220D01*
Y44860D01*
G01X415019Y58029D02*
X408671D01*
X405373Y61327D01*
X404023D01*
G01X415019Y50154D02*
X412029D01*
X407357Y45482D01*
G01X418345Y44560D02*
X410571D01*
X406449Y40438D01*
G01X373650Y21500D02*
X371978D01*
X370109Y23369D01*
X369900D01*
G01X373650Y21500D02*
Y25600D01*
G01X369900Y23369D02*
X363638D01*
G01X387150Y25800D02*
Y29150D01*
X387800Y29800D01*
G01X387150Y25800D02*
Y21700D01*
G01X376550Y65400D02*
Y69500D01*
G01Y65400D02*
X376013D01*
X370982Y60369D01*
X366838D01*
G01X380700Y74400D02*
Y73650D01*
X376550Y69500D01*
G01X376650Y38400D02*
Y42400D01*
X376750Y42500D01*
G01X376650Y38400D02*
X371300D01*
X369811Y39889D01*
X366838D01*
G01X373000Y44900D02*
X375400Y42500D01*
X376750D01*
G01Y46600D02*
Y50700D01*
G01X372900Y50000D02*
X376300Y46600D01*
X376750D01*
G01X366838Y47569D02*
X369769D01*
X372200Y50000D01*
X372900D01*
G01X366838Y50129D02*
X369829D01*
X372300Y52600D01*
X389300D01*
X390250Y51650D01*
Y50700D01*
G01Y46600D02*
X392268D01*
X393768Y48100D01*
G01X390250Y50700D02*
X392500D01*
X393768Y49432D01*
Y48100D01*
G01X376763Y55568D02*
Y59614D01*
X376767Y59618D01*
G01X373100Y55600D02*
X373600D01*
X373632Y55568D01*
X376763D01*
G01X373100Y55600D02*
X370344Y52844D01*
X370200D01*
X370045Y52689D01*
X366838D01*
G01Y55249D02*
X369449D01*
X376500Y62300D01*
X389600D01*
X390250Y61650D01*
Y59600D01*
G01D02*
X392200D01*
X393900Y57900D01*
G01X390250Y55500D02*
X392500D01*
X393900Y56900D01*
Y57900D01*
G01X390350Y69500D02*
Y72950D01*
X389800Y73500D01*
G01X390350Y65400D02*
X388450Y63500D01*
X376002D01*
X370311Y57809D01*
X366838D01*
G01X390350Y65400D02*
Y69500D01*
G01X356700Y86600D02*
X358200D01*
X363050Y91450D01*
X388350D01*
X395400Y98500D01*
X413000D01*
X430550Y116050D01*
X436700D01*
G01X398805Y66200D02*
Y68995D01*
X399318Y69508D01*
G01X381850Y30100D02*
X382383D01*
X384483Y32200D01*
X387100D01*
X390600Y35700D01*
X391200D01*
G01X363638Y25929D02*
X366870D01*
X367200Y26259D01*
X369659D01*
X372916Y29516D01*
X374800D01*
G01D02*
X375000D01*
X375584Y30100D01*
X378350D01*
G01X366838Y62929D02*
X370663D01*
X374100Y66366D01*
Y72700D01*
X375500Y74100D01*
G01X375600Y78250D02*
Y74200D01*
X375500Y74100D01*
G01X399770Y28592D02*
Y32730D01*
X399356Y33144D01*
Y39232D01*
X398510Y40078D01*
Y62610D01*
X401500Y65600D01*
Y71700D01*
X400192Y73008D01*
X399318D01*
G01X399360Y78152D02*
Y73050D01*
X399318Y73008D01*
G01X399770Y28592D02*
Y24839D01*
X400900Y23709D01*
X402609D01*
X405100Y26200D01*
X407424D01*
X408600Y27376D01*
G01X395148Y69508D02*
Y66350D01*
X395406Y66092D01*
G01X381850Y34200D02*
X382383D01*
X382483Y34100D01*
X386312D01*
X388006Y35794D01*
Y37706D01*
G01X363638Y28489D02*
X367589D01*
X370351Y31251D01*
Y31320D01*
G01X378350Y34200D02*
X376950Y32800D01*
X371831D01*
X370351Y31320D01*
G01X366838Y65489D02*
X370513D01*
X371448Y66424D01*
X372200Y67263D01*
Y71400D01*
X370800Y72800D01*
G01X371500Y78250D02*
Y73500D01*
X370800Y72800D01*
G01X397210Y28592D02*
Y32110D01*
X397456Y32356D01*
Y38444D01*
X396610Y39290D01*
Y61790D01*
X393248Y65152D01*
Y72548D01*
X393708Y73008D01*
X395148D01*
G01X418650Y22850D02*
Y26400D01*
G01X395130Y78152D02*
Y73026D01*
X395148Y73008D01*
G01X397210Y28592D02*
Y23399D01*
X398800Y21809D01*
X403397D01*
X405888Y24300D01*
X407424D01*
X408600Y23124D01*
G01X402500Y89124D02*
X401324Y90300D01*
X399500D01*
X398195Y88995D01*
Y82817D01*
X399360Y81652D01*
G01X375514Y85000D02*
X374900Y84386D01*
Y82450D01*
X375600Y81750D01*
G01X428188Y44860D02*
Y41312D01*
X429126Y40374D01*
Y33348D01*
X426415Y30637D01*
G01D02*
Y26565D01*
X426350Y26500D01*
G01X402500Y93376D02*
X401324Y92200D01*
X398712D01*
X396295Y89783D01*
Y82817D01*
X395130Y81652D01*
G01X372114Y85000D02*
X373000Y84114D01*
Y83250D01*
X371500Y81750D01*
G01X424250Y44860D02*
Y41450D01*
X421226Y38426D01*
Y31724D01*
X422250Y30700D01*
G01D02*
X422150Y30600D01*
Y26400D01*
G01X358700Y38100D02*
X358800D01*
X363149Y42449D01*
X366838D01*
G01X372400Y41100D02*
Y41800D01*
X369191Y45009D01*
X366838D01*
G01X438900Y13400D02*
Y15408D01*
X443396Y19904D01*
Y23617D01*
G01X430156Y44860D02*
Y42063D01*
X431026Y41193D01*
Y40919D01*
X434525Y37420D01*
G01X435287Y33058D02*
Y36658D01*
X434525Y37420D01*
G01X439418Y33085D02*
X439391Y33058D01*
X435287D01*
G01X437719Y48186D02*
X438410D01*
X444697Y41899D01*
G01X454550Y37100D02*
X450450D01*
X450400Y37050D01*
G01D02*
X449546D01*
X444697Y41899D01*
G01X437419Y58029D02*
X445011D01*
X445063Y57977D01*
G01X459157Y66114D02*
X461391Y63880D01*
Y60110D01*
G01D02*
Y59646D01*
X459251Y57506D01*
X445534D01*
X445063Y57977D01*
G01X437419Y56060D02*
X441807D01*
X441854Y56107D01*
X443821D01*
X444151Y55777D01*
X446811D01*
X447339Y56305D01*
X463799D01*
X463919Y56185D01*
G01X468381Y72070D02*
X466189D01*
X464444Y70325D01*
Y62816D01*
X465441Y61819D01*
Y60100D01*
G01D02*
Y57707D01*
X463919Y56185D01*
G01X443445Y29557D02*
Y23666D01*
X443396Y23617D01*
G01X447478Y29487D02*
X447570Y29579D01*
Y33313D01*
G01X434093Y44560D02*
X437340D01*
X444800Y37100D01*
G01X447570Y33313D02*
Y34330D01*
X444800Y37100D01*
G01X432125Y44860D02*
Y41792D01*
X432226Y41691D01*
Y41417D01*
X433326Y40318D01*
X436582D01*
X439800Y37100D01*
G01X443445Y33057D02*
Y33455D01*
X439800Y37100D01*
G01X429850Y22950D02*
Y26500D01*
G01X445238Y138269D02*
X445100Y138131D01*
Y124900D01*
X436700Y116500D01*
Y116050D01*
G01X448600Y109400D02*
X449173Y109973D01*
Y130394D01*
G01Y210394D02*
X450779Y212000D01*
X469000D01*
X471500Y209500D01*
G01X526110Y165952D02*
X530156D01*
X530160Y165948D01*
G01X520936Y175596D02*
Y171126D01*
X522293Y169769D01*
G01D02*
X526110Y165952D01*
G01X517530Y165852D02*
X521596D01*
X521600Y165848D01*
G01X515100Y169500D02*
X518967Y173367D01*
Y175596D01*
G01X517530Y165852D02*
Y167070D01*
X515100Y169500D01*
G01X534700Y173200D02*
X534500D01*
X532600Y175100D01*
X529865D01*
X528026Y176939D01*
Y178749D01*
G01X534700Y173200D02*
X535400Y172500D01*
X538200D01*
X541152Y175452D01*
Y176160D01*
G01X524873Y175596D02*
X526681D01*
X529077Y173200D01*
X531200D01*
X535600Y168800D01*
X537300D01*
X537600Y169100D01*
G01X541152Y172130D02*
X540930D01*
X538300Y169500D01*
X538000D01*
X537600Y169100D01*
G01X544652Y176160D02*
X545717Y175095D01*
X550200D01*
X551376Y176271D01*
G01X544652Y172130D02*
X545717Y173195D01*
X550200D01*
X551376Y172019D01*
G01X522904Y175596D02*
Y172996D01*
X525900Y170000D01*
X528800D01*
G01X534348Y165908D02*
Y166376D01*
X530724Y170000D01*
X528800D01*
G01X534348Y162408D02*
Y159348D01*
X530000Y155000D01*
X527690D01*
X513162Y140472D01*
Y109838D01*
X517800Y105200D01*
Y103400D01*
X517900Y103300D01*
G54D67*
X468381Y66114D03*
X459157D03*
Y72070D03*
X468381D03*
G54D58*
X418345Y44560D03*
Y67560D03*
X434093Y44560D03*
Y67560D03*
G54D49*
X150588Y-42D03*
X153148D03*
X155708D03*
Y7358D03*
X153148D03*
X150588D03*
G54D77*
G01X130551Y-63909D02*
Y-59640D01*
G03X130064Y-58464I-1663J0D01*
G02X129577Y-57288I1176J1176D01*
G01Y-56330D01*
X130900Y-53000D01*
X145284Y-40948D01*
X146484Y-39742D01*
X146496D01*
X146498Y-39740D01*
X176490Y3092D01*
X189605Y77471D01*
X176600Y114002D01*
X176596Y114011D01*
X176600Y114023D01*
X170084Y125634D01*
X169800Y126800D01*
G02X169500Y129300I10267J2500D01*
G01Y130890D01*
G02X171020Y134560I5190J0D01*
G03X174580Y139230I-4396J7043D01*
G02X178017Y142629I4820J-1436D01*
G01X179140Y142950D01*
G03X181948Y146443I-1066J3732D01*
G01X182140Y149550D01*
G03X180651Y152135I-2698J167D01*
G01X180204Y152359D01*
X180203D01*
G02X179980Y153030I224J447D01*
G01X181458Y155984D01*
G01X177518Y148109D02*
X178996Y151062D01*
G02X179667Y151285I447J-224D01*
G01X179668D01*
X180114Y151061D01*
G02X180942Y149624I-672J-1344D01*
G01X180750Y146517D01*
G02X178810Y144104I-2676J165D01*
G01X177687Y143783D01*
G03X173430Y139573I1713J-5989D01*
G02X170278Y135513I-6806J2030D01*
G03X168300Y130889I4412J-4622D01*
G01Y129300D01*
G03X168634Y126516I11767J0D01*
G01X168957Y125190D01*
X175453Y113613D01*
X175457Y113604D01*
X175466Y113607D01*
X188368Y77367D01*
X175354Y3562D01*
X175353D01*
X160494Y-17658D01*
X145636Y-38878D01*
X145628Y-38884D01*
Y-38900D01*
X145626Y-38902D01*
X144471Y-40062D01*
X136611Y-46648D01*
X135639Y-46562D01*
X134489Y-47526D01*
X134403Y-48498D01*
X133253Y-49461D01*
X132281Y-49375D01*
X131131Y-50339D01*
X131046Y-51311D01*
X129896Y-52274D01*
X129785Y-52556D01*
X128377Y-56100D01*
Y-56834D01*
G02X127890Y-58010I-1663J0D01*
G03X127402Y-59188I1178J-1178D01*
G01Y-63909D01*
G01X205078Y130394D02*
X204155Y132340D01*
X203604Y133444D01*
G03X202933Y133668I-447J-223D01*
G01X202932D01*
X202923Y133663D01*
X202671Y133538D01*
G03X201716Y131061I2734J-2477D01*
G01X202359Y124830D01*
X202510Y124313D01*
G03X202529Y124258I481J135D01*
G01X206060Y115939D01*
G02X206100Y115743I-460J-196D01*
G01Y88413D01*
X188800Y-700D01*
X172246Y-43674D01*
X172642Y-44566D01*
X172103Y-45966D01*
X171211Y-46361D01*
X170672Y-47761D01*
X171067Y-48653D01*
X170528Y-50053D01*
X169636Y-50449D01*
X167372Y-56327D01*
Y-57323D01*
X167375Y-57376D01*
G03X167860Y-58459I1661J94D01*
G01X167861Y-58460D01*
G02X168347Y-59635I-1177J-1175D01*
G01Y-63909D01*
G01X185393Y138269D02*
X183917Y135314D01*
G03X184141Y134643I448J-223D01*
G01X184142D01*
X184147Y134641D01*
X184588Y134421D01*
G02X185940Y132150I-1095J-2190D01*
G01X186500Y128300D01*
X195440Y78299D01*
X194141Y70934D01*
X181888Y1424D01*
X157923Y-56621D01*
Y-57536D01*
G03X158410Y-58713I1666J0D01*
G01X158556Y-58859D01*
G02X158898Y-59683I-822J-824D01*
G01Y-63909D01*
G01X201143Y138269D02*
X201822Y137007D01*
X202619Y135412D01*
G02X202395Y134741I-448J-223D01*
G01X202394D01*
X202388Y134738D01*
X201948Y134520D01*
G03X200516Y130995I3457J-3458D01*
G01X201176Y124597D01*
X201183Y124574D01*
X201385Y123881D01*
X204900Y115600D01*
Y88529D01*
X187642Y-364D01*
X166214Y-55994D01*
X166172Y-56104D01*
Y-57445D01*
G02X165830Y-58269I-1164J0D01*
G01X165684Y-58415D01*
G03X165197Y-59592I1179J-1177D01*
G01Y-63909D01*
G01X181458Y130394D02*
X182932Y133346D01*
G02X183603Y133570I447J-223D01*
G01X183604D01*
X184052Y133347D01*
G02X184740Y132190I-559J-1116D01*
G01X184737Y132083D01*
X185312Y128128D01*
X185315Y128108D01*
X194221Y78298D01*
X192959Y71142D01*
X180728Y1761D01*
X160933Y-46185D01*
X160032Y-46559D01*
X159460Y-47945D01*
X159834Y-48847D01*
X159262Y-50233D01*
X158361Y-50608D01*
X157788Y-51994D01*
X158163Y-52895D01*
X156723Y-56383D01*
Y-57811D01*
G02X156236Y-58987I-1663J0D01*
G03X155748Y-60164I1175J-1177D01*
G01Y-63909D01*
G01X275943Y130394D02*
X274638Y133106D01*
X274480Y133264D01*
G03X273229Y133149I-578J-578D01*
G03X272581Y131061I3041J-2088D01*
G01Y129159D01*
X272015Y125559D01*
X272000Y125500D01*
X227440Y-43526D01*
X227931Y-44369D01*
X227549Y-45819D01*
X226706Y-46310D01*
X226324Y-47761D01*
X226815Y-48604D01*
X226433Y-50054D01*
X225589Y-50546D01*
X224065Y-56328D01*
Y-57376D01*
G03X224552Y-58552I1663J0D01*
G02X225040Y-59730I-1178J-1178D01*
G01Y-63909D01*
G01X260198Y130394D02*
X259848Y131193D01*
X258724Y133444D01*
G03X258053Y133668I-447J-223D01*
G01X258052D01*
X258043Y133663D01*
X257791Y133538D01*
G03X256836Y131061I2734J-2477D01*
G01Y129360D01*
X216854Y-45361D01*
X217373Y-46187D01*
X217038Y-47649D01*
X216212Y-48168D01*
X215877Y-49630D01*
X216396Y-50457D01*
X216061Y-51919D01*
X215235Y-52438D01*
X214900Y-53900D01*
X214616Y-56306D01*
Y-56806D01*
G03X215054Y-57863I1494J0D01*
G02X215591Y-59159I-1295J-1296D01*
G01Y-63909D01*
G01X236573Y130394D02*
X235836Y131968D01*
X235099Y133444D01*
G03X234428Y133668I-447J-223D01*
G01X234427D01*
X234418Y133663D01*
X234166Y133538D01*
G03X233211Y131061I2734J-2477D01*
G01Y129861D01*
X207162Y-42319D01*
X207741Y-43105D01*
X207516Y-44588D01*
X206731Y-45167D01*
X206506Y-46650D01*
X207085Y-47435D01*
X206861Y-48918D01*
X206076Y-49497D01*
X205492Y-53355D01*
X205166Y-57447D01*
X205165Y-57448D01*
X205168D01*
X205167Y-57449D01*
G03X205654Y-58625I1663J0D01*
G02X206142Y-59803I-1178J-1178D01*
G01Y-63909D01*
G01X220828Y130394D02*
X219907Y132337D01*
X219354Y133444D01*
G03X218683Y133668I-447J-223D01*
G01X218682D01*
X218673Y133663D01*
X218421Y133538D01*
G03X217467Y131060I2735J-2475D01*
G01Y131008D01*
X217195Y127879D01*
X197358Y-42606D01*
X197964Y-43371D01*
X197790Y-44861D01*
X197025Y-45466D01*
X196852Y-46956D01*
X197457Y-47721D01*
X197284Y-49211D01*
X196519Y-49817D01*
X196300Y-51699D01*
Y-51700D01*
X195718Y-56000D01*
Y-57529D01*
G03X196206Y-58706I1663J0D01*
G02X196693Y-59882I-1176J-1176D01*
G01Y-63909D01*
G01X307443Y130394D02*
X307133Y131113D01*
X305969Y133444D01*
G03X305326Y133711I-501J-298D01*
G01X305325D01*
G03X305315Y133708I162J-559D01*
G03X305036Y133538I151J-562D01*
G03X304081Y131061I2734J-2477D01*
G01Y129355D01*
X303873Y128175D01*
X303853Y128167D01*
X303656Y127691D01*
X295395Y106439D01*
X287887Y87123D01*
X283646Y76214D01*
X283448Y75752D01*
X245636Y-47514D01*
X246093Y-48376D01*
X245653Y-49810D01*
X244791Y-50267D01*
X244351Y-51701D01*
X244808Y-52563D01*
X244369Y-53998D01*
X243507Y-54455D01*
X242962Y-56230D01*
Y-57244D01*
G03X243449Y-58420I1663J0D01*
G02X243937Y-59598I-1178J-1178D01*
G01Y-63909D01*
G01X291693Y130394D02*
Y130492D01*
X290219Y133444D01*
G03X289548Y133668I-447J-223D01*
G01X289547D01*
X289538Y133663D01*
X289286Y133538D01*
G03X288332Y131146I2734J-2477D01*
G03X288331Y131061I3688J-86D01*
G01X288089Y126296D01*
X236403Y-44486D01*
X236864Y-45346D01*
X236430Y-46782D01*
X235569Y-47242D01*
X235135Y-48678D01*
X235595Y-49538D01*
X235161Y-50974D01*
X234300Y-51434D01*
X233866Y-52870D01*
X233514Y-56230D01*
Y-57396D01*
G03X234002Y-58573I1663J0D01*
G02X234489Y-59749I-1176J-1176D01*
G01Y-63909D01*
G01X272008Y138269D02*
X272243Y137896D01*
X273189Y136003D01*
G02X273296Y135699I-1174J-584D01*
G01Y135323D01*
G02X273084Y134811I-724J0D01*
G01X272813Y134519D01*
G03X272646Y134343I3462J-3452D01*
G03X272239Y133828I3623J-3282D01*
G03X271381Y131062I4030J-2766D01*
G01Y129253D01*
X270839Y125806D01*
X222904Y-56024D01*
X222865Y-56172D01*
Y-57247D01*
G02X222379Y-58422I-1663J0D01*
G01X222378Y-58423D01*
G03X221890Y-59599I1176J-1177D01*
G01Y-63909D01*
G01X256258Y138269D02*
X256622Y137640D01*
X257739Y135412D01*
G02X257515Y134741I-448J-223D01*
G01X257514D01*
X257068Y134519D01*
G03X255636Y131062I3457J-3457D01*
G01Y129496D01*
X213730Y-53633D01*
X213716Y-53694D01*
X213715Y-53695D01*
X213416Y-56235D01*
Y-56806D01*
G02X213078Y-57621I-1152J0D01*
G01X212928Y-57771D01*
G03X212441Y-58948I1179J-1177D01*
G01Y-63909D01*
G01X202992D02*
Y-59705D01*
G02X203480Y-58528I1663J0D01*
G03X203967Y-57352I-1176J1176D01*
G01X203969Y-57350D01*
X204222Y-54180D01*
X204283Y-53413D01*
X204299Y-53217D01*
X232011Y129952D01*
Y131060D01*
G02Y131062I4889J1D01*
G02X233443Y134519I4889J0D01*
G01X233889Y134741D01*
X233890D01*
G03X234114Y135412I-224J448D01*
G01X233130Y137382D01*
X232638Y138269D01*
G01X216888D02*
X217857Y136433D01*
X218369Y135412D01*
G02X218145Y134741I-448J-223D01*
G01X218144D01*
X217698Y134519D01*
G03X216266Y131060I3457J-3457D01*
G01X216000Y128000D01*
X195109Y-51549D01*
X194518Y-55919D01*
Y-57393D01*
G02X194031Y-58569I-1663J0D01*
G03X193544Y-59745I1176J-1176D01*
G01Y-63909D01*
G01X240788D02*
Y-59612D01*
G02X241275Y-58436I1663J0D01*
G03X241762Y-57260I-1176J1176D01*
G01Y-56050D01*
X282319Y76166D01*
X282535Y76668D01*
X294276Y106873D01*
X302542Y128138D01*
X302546Y128150D01*
X302547D01*
X302744Y128626D01*
X302737Y128645D01*
X302881Y129461D01*
Y131062D01*
G02X304146Y134344I4889J0D01*
G02X304313Y134519I3619J-3287D01*
G01X304542Y134748D01*
G03X304731Y135916I-715J715D01*
G01X303503Y138367D01*
Y138269D01*
G01X231339Y-63909D02*
Y-59561D01*
G02X231827Y-58384I1663J0D01*
G03X232314Y-57208I-1176J1176D01*
G01Y-56167D01*
X232686Y-52608D01*
X286897Y126503D01*
X287064Y129791D01*
X287130Y131078D01*
Y131122D01*
G02Y131158I4890J18D01*
G01X287132Y131173D01*
G02X288563Y134519I4888J-111D01*
G01X289009Y134741D01*
X289010D01*
G03X289234Y135412I-224J448D01*
G01X288464Y136953D01*
X287758Y138269D01*
G01X262835Y-63909D02*
Y-59894D01*
G03X262349Y-58719I-1663J0D01*
G01X262348Y-58718D01*
G02X261860Y-57542I1176J1177D01*
G01Y-55965D01*
X293492Y72720D01*
X294135Y74130D01*
X294151Y74165D01*
X294163Y74169D01*
X294165Y74172D01*
X324851Y117996D01*
X334851Y124042D01*
X337500Y124900D01*
X341500Y126200D01*
X342963Y127667D01*
X343458Y129464D01*
Y131163D01*
G03X342068Y134519I-4746J0D01*
G01X341622Y134741D01*
X341621D01*
G02X341397Y135412I224J448D01*
G01X342381Y137382D01*
X342873Y138269D01*
G01X327128D02*
X326177Y136466D01*
X325650Y135413D01*
G03X325873Y134742I447J-224D01*
G01X325874D01*
X326321Y134518D01*
G02X327933Y130626I-3892J-3892D01*
G01Y129166D01*
X327345Y126727D01*
X326082Y124924D01*
X320901Y121298D01*
X314927Y112764D01*
X314923Y112761D01*
X314917Y112752D01*
X312500Y109300D01*
X289479Y76423D01*
X252412Y-56330D01*
Y-57523D01*
G03X252899Y-58699I1663J0D01*
G02X253386Y-59875I-1176J-1176D01*
G01Y-63909D01*
G01X338938Y130394D02*
X339464Y131545D01*
X340412Y133444D01*
G02X341083Y133668I447J-223D01*
G01X341084D01*
X341344Y133538D01*
G02X342257Y131163I-2632J-2375D01*
G01X342258Y131164D01*
Y129627D01*
X341889Y128291D01*
X340854Y127252D01*
X338991Y126647D01*
X337129Y126042D01*
X334349Y125141D01*
X324013Y118892D01*
X293053Y74678D01*
X293058Y74662D01*
X292353Y73115D01*
X263317Y-45010D01*
X262482Y-45515D01*
X262124Y-46972D01*
X262629Y-47807D01*
X262271Y-49263D01*
X261437Y-49769D01*
X261079Y-51225D01*
X261584Y-52060D01*
X260599Y-56067D01*
X260660Y-56083D01*
Y-57361D01*
G02X260172Y-58539I-1666J0D01*
G03X259685Y-59715I1176J-1176D01*
G01Y-63909D01*
G01X323188Y130394D02*
X323811Y131737D01*
X324666Y133445D01*
G02X325337Y133668I447J-224D01*
G01X325598Y133537D01*
G02X326732Y130626I-3169J-2911D01*
G01X326733Y130627D01*
Y129309D01*
X326231Y127230D01*
X325919Y126783D01*
X325220Y125786D01*
X320039Y122160D01*
X313935Y113444D01*
X313933Y113441D01*
X313887Y113375D01*
X311516Y109989D01*
X288378Y76943D01*
X253839Y-46756D01*
X252989Y-47235D01*
X252586Y-48680D01*
X253065Y-49530D01*
X252661Y-50975D01*
X251811Y-51454D01*
X251408Y-52898D01*
X251887Y-53749D01*
X251212Y-56165D01*
Y-57698D01*
G02X250724Y-58876I-1666J0D01*
G03X250237Y-60052I1176J-1176D01*
G01Y-63909D01*
G01X437363Y138269D02*
X436788Y137219D01*
X435885Y135413D01*
G03X436108Y134742I447J-224D01*
G01X436109D01*
X436556Y134518D01*
G02X437970Y131104I-3414J-3414D01*
G01Y129405D01*
X437345Y127643D01*
X436686Y126563D01*
X435581Y124992D01*
X435409Y124872D01*
X408720Y106184D01*
X349131Y95676D01*
X345297Y93882D01*
X339848Y86693D01*
X321692Y60766D01*
X316204Y29634D01*
Y29633D01*
X310716Y-1501D01*
X314400Y-42800D01*
X316200Y-47500D01*
X318392Y-50829D01*
X318970Y-53864D01*
X318553Y-56230D01*
Y-57035D01*
G03X319040Y-58212I1666J0D01*
G01X319186Y-58358D01*
G02X319528Y-59182I-822J-824D01*
G01Y-63909D01*
G01X310079D02*
Y-59439D01*
G03X309592Y-58263I-1663J0D01*
G02X309104Y-57085I1178J1178D01*
G01Y-55518D01*
X308946Y-54281D01*
X305342Y-4091D01*
X317142Y62879D01*
X317135Y62898D01*
X317333Y63374D01*
X340000Y95900D01*
X345374Y100168D01*
X402446Y110232D01*
X410431Y115822D01*
X419891Y123332D01*
X422355Y130157D01*
Y130997D01*
G03X420809Y134518I-5294J-225D01*
G01X420363Y134741D01*
X420361D01*
G02X420137Y135412I224J448D01*
G01X421121Y137382D01*
X421613Y138269D01*
G01X405868D02*
X405129Y136890D01*
X404390Y135413D01*
G03X404613Y134742I447J-224D01*
G01X404614D01*
X404618Y134740D01*
X404617D01*
X404745Y134676D01*
X405060Y134518D01*
G02X406295Y131536I-2981J-2981D01*
G01Y128834D01*
X406061Y127501D01*
X401397Y120841D01*
X396283Y117260D01*
X390750Y113387D01*
X386342Y112610D01*
X386340Y112609D01*
X343958Y105134D01*
X337488Y100606D01*
X333666Y95149D01*
X333613Y95073D01*
X323227Y80238D01*
X312839Y65403D01*
Y65404D01*
X300421Y-5014D01*
X299382Y-32988D01*
X299960Y-53836D01*
X299891Y-55536D01*
Y-55539D01*
X299894Y-55542D01*
X299651Y-57225D01*
Y-57231D01*
X299656Y-57232D01*
Y-57238D01*
G03X300143Y-58414I1663J0D01*
G02X300630Y-59590I-1176J-1176D01*
G01Y-63909D01*
G01X390118Y138269D02*
X389626Y137382D01*
X388642Y135412D01*
G03X388866Y134741I448J-223D01*
G01X388867D01*
X389044Y134653D01*
X389311Y134522D01*
G02X390865Y130772I-3745J-3749D01*
G01X390190Y126894D01*
X387811Y123461D01*
X382893Y119845D01*
X377976Y117825D01*
X373197Y115861D01*
X372949Y115788D01*
X341494Y110242D01*
X334912Y105631D01*
X329991Y98596D01*
X329990D01*
X308187Y67458D01*
X294747Y-8764D01*
X290524Y-52182D01*
X290207Y-57389D01*
G03X290694Y-58565I1663J0D01*
G02X291181Y-59741I-1176J-1176D01*
G01Y-63909D01*
G01X374368Y138269D02*
X373640Y136909D01*
X372892Y135412D01*
G03X373116Y134741I448J-223D01*
G01X373117D01*
X373563Y134519D01*
X373564Y134518D01*
G02X373728Y134347I-3714J-3726D01*
G02X375104Y130799I-3885J-3548D01*
G01Y129309D01*
X375086Y129291D01*
X374723Y127232D01*
X374704Y127223D01*
X374403Y126496D01*
X374053Y125651D01*
X373431Y124763D01*
X371673Y122252D01*
X368008Y119688D01*
X339411Y114644D01*
X330297Y108261D01*
X327729Y104594D01*
X327281Y103953D01*
X327096Y103689D01*
X326205Y102416D01*
X326203Y102413D01*
X326030Y102166D01*
X326028Y102165D01*
X314638Y85897D01*
X303070Y69377D01*
Y69378D01*
X282908Y-44964D01*
X282889Y-45075D01*
X280758Y-56338D01*
Y-56982D01*
X280759Y-57017D01*
G03X281245Y-58146I1665J48D01*
G01X281391Y-58292D01*
G02X281733Y-59116I-822J-824D01*
G01Y-63909D01*
G01X272284D02*
Y-59338D01*
G03X271942Y-58514I-1164J0D01*
G01X271796Y-58368D01*
G02X271309Y-57191I1179J1177D01*
G01Y-56230D01*
X298659Y71963D01*
X326932Y112340D01*
X336520Y119054D01*
X354480Y122221D01*
X357362Y124238D01*
X358882Y126409D01*
X359302Y128785D01*
X359251Y131742D01*
Y131744D01*
G03X357816Y134518I-2618J404D01*
G01X357382Y134735D01*
X357369Y134742D01*
X357368D01*
G02X357145Y135413I224J447D01*
G01X357884Y136890D01*
X358623Y138269D01*
G01X316378Y-63909D02*
Y-59322D01*
G02X316866Y-58145I1663J0D01*
G03X317353Y-56969I-1176J1176D01*
G01Y-56125D01*
X317749Y-53872D01*
X317258Y-51289D01*
X315150Y-48088D01*
X315149Y-48086D01*
X315126Y-48051D01*
X313219Y-43073D01*
X311362Y-22257D01*
X309506Y-1449D01*
X320556Y61236D01*
X338878Y87400D01*
X344519Y94844D01*
X348766Y96831D01*
X408250Y107320D01*
X427544Y120830D01*
X427714Y121791D01*
X428942Y122652D01*
X429903Y122482D01*
X431132Y123343D01*
X431302Y124304D01*
X432530Y125164D01*
X433491Y124995D01*
X434720Y125855D01*
X435681Y127222D01*
X436255Y128162D01*
X436770Y129612D01*
Y131105D01*
X436769Y131104D01*
G03X435831Y133538I-3627J0D01*
G01X435572Y133668D01*
G03X434901Y133445I-224J-447D01*
G01X434356Y132355D01*
X433423Y130394D01*
G01X417678D02*
X418415Y131968D01*
X419152Y133444D01*
G02X419823Y133668I447J-223D01*
G01X419824D01*
X420086Y133537D01*
G02X421155Y130969I-3025J-2766D01*
G01Y130367D01*
X418878Y124060D01*
X409713Y116785D01*
X401976Y111368D01*
X344866Y101297D01*
X339115Y96731D01*
X339016Y96587D01*
X316274Y63955D01*
X316224Y63835D01*
X316026Y63359D01*
X316006Y63351D01*
X304134Y-4029D01*
X307041Y-44511D01*
X306402Y-45248D01*
X306510Y-46745D01*
X307247Y-47383D01*
X307355Y-48879D01*
X306716Y-49617D01*
X306823Y-51113D01*
X307561Y-51752D01*
X307751Y-54400D01*
X307904Y-55595D01*
Y-57218D01*
G02X307417Y-58394I-1663J0D01*
G03X306929Y-59572I1178J-1178D01*
G01Y-63909D01*
G01X401928Y130394D02*
X402505Y131646D01*
X403406Y133445D01*
G02X404077Y133668I447J-224D01*
G01X404334Y133539D01*
G02X405095Y131537I-2255J-2003D01*
G01Y128939D01*
X404925Y127971D01*
X400535Y121703D01*
X395594Y118244D01*
X390279Y114523D01*
X388669Y114239D01*
X343488Y106270D01*
X336626Y101469D01*
X332629Y95761D01*
Y95760D01*
X311703Y65874D01*
X299224Y-4887D01*
X298181Y-32982D01*
X298504Y-44624D01*
X297833Y-45332D01*
X297875Y-46832D01*
X298584Y-47502D01*
X298625Y-49002D01*
X297955Y-49711D01*
X297996Y-51210D01*
X298705Y-51881D01*
X298759Y-53828D01*
X298702Y-55238D01*
X298691Y-55488D01*
Y-55491D01*
X298688Y-55494D01*
X298463Y-57054D01*
Y-57061D01*
X298456Y-57060D01*
Y-57066D01*
G02X297969Y-58242I-1663J0D01*
G03X297481Y-59420I1178J-1178D01*
G01Y-63909D01*
G01X386183Y130394D02*
X386920Y131968D01*
X387657Y133444D01*
G02X388328Y133668I447J-223D01*
G01X388329D01*
X388332Y133666D01*
X388333D01*
X388461Y133602D01*
X388591Y133538D01*
G02X389663Y130869I-3026J-2765D01*
G01X389052Y127361D01*
X386938Y124310D01*
X382300Y120900D01*
X372741Y116971D01*
X341023Y111378D01*
X337514Y108919D01*
X334049Y106493D01*
X329365Y99796D01*
X329364D01*
X323556Y91501D01*
X318105Y83716D01*
X307051Y67928D01*
X293557Y-8601D01*
X290175Y-43368D01*
X289422Y-43988D01*
X289276Y-45481D01*
X289896Y-46235D01*
X289751Y-47728D01*
X288998Y-48348D01*
X288852Y-49840D01*
X289472Y-50594D01*
X289327Y-52087D01*
X289009Y-57317D01*
X289008D01*
X289007Y-57316D01*
G02X288521Y-58491I-1663J0D01*
G01X288520Y-58492D01*
G03X288032Y-59668I1176J-1177D01*
G01Y-63909D01*
G01X278583D02*
Y-59406D01*
G02X279070Y-58230I1663J0D01*
G03X279558Y-57052I-1178J1178D01*
G01Y-56225D01*
X280080Y-53466D01*
X279530Y-52660D01*
X279809Y-51186D01*
X280615Y-50637D01*
X280894Y-49163D01*
X280344Y-48356D01*
X280623Y-46883D01*
X281429Y-46333D01*
X281708Y-44859D01*
X301934Y69848D01*
X325044Y102853D01*
X325046Y102856D01*
X325219Y103103D01*
X325221Y103104D01*
X325848Y104001D01*
X326745Y105283D01*
X329435Y109123D01*
X338941Y115780D01*
X367538Y120824D01*
X370811Y123114D01*
X372994Y126232D01*
X373595Y127682D01*
X373587Y127702D01*
X373904Y129499D01*
Y130798D01*
G03X372841Y133537I-4061J0D01*
G01X372579Y133668D01*
X372578D01*
G03X371907Y133444I-224J-447D01*
G01X371170Y131968D01*
X370433Y130394D01*
G01X354683D02*
X355090Y131305D01*
X356161Y133445D01*
G02X356832Y133668I447J-224D01*
G01X356833D01*
X356844Y133662D01*
X357279Y133444D01*
G02X358065Y131927I-646J-1297D01*
G01X358049Y131826D01*
X358100Y128880D01*
X357746Y126880D01*
X356500Y125100D01*
X354010Y123357D01*
X336050Y120190D01*
X326070Y113202D01*
X297536Y72452D01*
X272680Y-44052D01*
X271861Y-44583D01*
X271548Y-46050D01*
X272079Y-46869D01*
X271766Y-48336D01*
X270947Y-48867D01*
X270634Y-50334D01*
X271165Y-51152D01*
X270109Y-56103D01*
Y-57014D01*
G02X269623Y-58189I-1663J0D01*
G01X269622Y-58190D01*
G03X269134Y-59366I1176J-1177D01*
G01Y-63909D01*
G01X324021Y-46464D02*
G03X322632Y-47853I0J-1389D01*
G01Y-48241D01*
G03X322983Y-49090I1200J-1D01*
G01X323213Y-49321D01*
G03X324470Y-49841I1256J1257D01*
G01X324597D01*
G02X326770Y-50741I0J-3073D01*
G01X326893Y-50865D01*
G02X328002Y-53541I-2676J-2677D01*
G01Y-56983D01*
G03X328490Y-58161I1666J0D01*
G02X328977Y-59337I-1176J-1176D01*
G01Y-63909D01*
G01X338426D02*
Y-59337D01*
G03X337939Y-58161I-1663J0D01*
G02X337451Y-56983I1178J1178D01*
G01Y-52322D01*
G03X335370Y-50241I-2081J0D01*
G02X333833Y-49605I-1J2173D01*
G01X333170Y-48941D01*
G02X332870Y-48217I724J724D01*
G01Y-47641D01*
G02X334047Y-46464I1177J0D01*
G01X334221D01*
G01X320021D02*
G02X321432Y-47875I0J-1411D01*
G01Y-48247D01*
G03X322132Y-49937I2390J0D01*
G01X322363Y-50169D01*
G03X324470Y-51041I2105J2106D01*
G01X324598D01*
G02X325919Y-51589I-3J-1872D01*
G01X326042Y-51713D01*
X326044Y-51714D01*
G02X326802Y-53542I-1826J-1829D01*
G01Y-57020D01*
G02X326314Y-58196I-1664J1D01*
G01X326313Y-58197D01*
G03X325827Y-59372I1177J-1175D01*
G01Y-63909D01*
G01X335276D02*
Y-59372D01*
G02X335762Y-58197I1663J0D01*
G01X335763Y-58196D01*
G03X336251Y-57020I-1176J1177D01*
G01Y-52322D01*
G03X335370Y-51441I-881J0D01*
G02X332984Y-50454I-2J3374D01*
G01X332320Y-49790D01*
G02X331670Y-48218I1575J1572D01*
G01Y-47641D01*
G03X330493Y-46464I-1177J0D01*
G01X330221D01*
G01X340421D02*
X340693D01*
G02X341870Y-47641I0J-1177D01*
G01Y-48218D01*
G03X342592Y-49960I2465J1D01*
G01X344921Y-52290D01*
G02X345698Y-54167I-1877J-1877D01*
G01X345699Y-54166D01*
Y-56983D01*
X345700D01*
Y-57020D01*
G02X345212Y-58196I-1664J1D01*
G01X345211Y-58197D01*
G03X344725Y-59372I1177J-1175D01*
G01Y-63909D01*
G01X344421Y-46464D02*
X344247D01*
G03X343070Y-47641I0J-1177D01*
G01Y-48217D01*
G03X343440Y-49110I1263J0D01*
G01X345770Y-51441D01*
G02X346899Y-54167I-2726J-2726D01*
G01Y-56983D01*
G03X347387Y-58161I1666J0D01*
G02X347874Y-59337I-1176J-1176D01*
G01Y-63909D01*
G01X327128Y218269D02*
X325650Y215315D01*
G03X325873Y214644I447J-224D01*
G01X325874D01*
X325887Y214637D01*
X326321Y214420D01*
G02X327773Y210915I-3505J-3505D01*
G01Y208840D01*
X327967Y207741D01*
X329134Y206074D01*
X369112Y178081D01*
X457092Y162568D01*
X463472Y158101D01*
X467479Y152380D01*
X482127Y66949D01*
X482112Y66936D01*
Y66922D01*
X482041Y65221D01*
Y65222D01*
X450500Y-54900D01*
X450501D01*
X450203Y-56245D01*
X449958Y-57343D01*
X450029Y-58240D01*
G03X450517Y-59417I1663J0D01*
G02X451004Y-60593I-1176J-1176D01*
G01Y-64309D01*
G01X460453D02*
Y-59936D01*
G03X459965Y-58758I-1666J0D01*
G02X459478Y-57582I1176J1176D01*
G01Y-57577D01*
X459472Y-57578D01*
Y-57573D01*
X459406Y-57077D01*
X459700Y-55000D01*
X487318Y65697D01*
X487313Y66066D01*
X473706Y145699D01*
X473044Y149576D01*
X473043D01*
X472138Y154875D01*
X471096Y156364D01*
X467827Y161030D01*
X457069Y168564D01*
X454113Y169085D01*
X383001Y181625D01*
X381016Y181975D01*
X378308Y182453D01*
X344789Y205922D01*
X344442Y206418D01*
X344317Y206598D01*
X343484Y211009D01*
G03X342068Y214421I-4835J-7D01*
G01X341622Y214643D01*
X341621D01*
G02X341397Y215314I224J448D01*
G01X342873Y218269D01*
G01X447854Y-64309D02*
Y-60635D01*
G02X448342Y-59459I1664J-1D01*
G01X448343Y-59458D01*
G03X448829Y-58283I-1177J1175D01*
G01X448786Y-57083D01*
X449339Y-54596D01*
X450104Y-51683D01*
X449612Y-50840D01*
X449993Y-49390D01*
X450835Y-48897D01*
X451216Y-47447D01*
X450724Y-46604D01*
X451105Y-45153D01*
X451948Y-44661D01*
X451947D01*
X452393Y-42962D01*
X480595Y64442D01*
X480847Y65401D01*
Y65423D01*
X480911Y66937D01*
X480900Y67000D01*
X466341Y151912D01*
X462610Y157239D01*
X456622Y161432D01*
X370881Y176550D01*
X368642Y176945D01*
X367119Y178011D01*
X328272Y205212D01*
X326831Y207271D01*
X326573Y208734D01*
Y210914D01*
G03X325597Y213440I-3757J0D01*
G01X325349Y213564D01*
X325338Y213570D01*
X325337D01*
G03X324666Y213347I-224J-447D01*
G01X323188Y210394D01*
G01X338938D02*
X340412Y213346D01*
G02X341083Y213570I447J-223D01*
G01X341084D01*
X341093Y213565D01*
X341345Y213440D01*
G02X342283Y211002I-2697J-2437D01*
G01Y210897D01*
X343185Y206121D01*
X343383Y205838D01*
X343926Y205060D01*
X377838Y181317D01*
X380807Y180792D01*
X453905Y167903D01*
X456599Y167428D01*
X466965Y160168D01*
X471000Y154407D01*
X472522Y145497D01*
X472523D01*
X486114Y65956D01*
X486116Y65825D01*
X460524Y-46017D01*
X459697Y-46536D01*
X459363Y-47998D01*
X459881Y-48825D01*
X459547Y-50287D01*
X458720Y-50805D01*
X458386Y-52268D01*
X458904Y-53094D01*
X458518Y-54782D01*
X458511Y-54832D01*
X458194Y-57072D01*
X458281Y-57730D01*
X458282D01*
Y-57735D01*
X458278Y-57736D01*
Y-57741D01*
G02X457792Y-58916I-1663J0D01*
G01X457791Y-58917D01*
G03X457303Y-60093I1176J-1177D01*
G01Y-64309D01*
G01X357323Y-63909D02*
Y-59337D01*
G03X356836Y-58161I-1663J0D01*
G02X356348Y-56983I1178J1178D01*
G01Y-53444D01*
G03X355270Y-50841I-3681J0D01*
G01X353711Y-49282D01*
G02X353270Y-48217I1065J1065D01*
G01Y-47641D01*
G02X354447Y-46464I1177J0D01*
G01X354621D01*
G01X366772Y-63909D02*
Y-59337D01*
G03X366285Y-58161I-1663J0D01*
G02X365797Y-56983I1178J1178D01*
G01Y-53328D01*
G03X364270Y-49641I-5214J0D01*
G01X363911Y-49282D01*
G02X363470Y-48217I1065J1065D01*
G01Y-47641D01*
G02X364647Y-46464I1177J0D01*
G01X364821D01*
G01X375021D02*
X374847D01*
G03X373670Y-47641I0J-1177D01*
G01Y-49141D01*
G03X374270Y-51041I2472J-264D01*
G02X375246Y-53641I-2975J-2600D01*
G01Y-56983D01*
G03X375734Y-58161I1666J0D01*
G02X376221Y-59337I-1176J-1176D01*
G01Y-63909D01*
G01X385221Y-46464D02*
X385047D01*
G03X383870Y-47641I0J-1177D01*
G01Y-49317D01*
G02X384695Y-56983I-35204J-7666D01*
G03X385183Y-58161I1666J0D01*
G02X385670Y-59337I-1176J-1176D01*
G01Y-63909D01*
G01X395118D02*
Y-59337D01*
G03X394631Y-58161I-1663J0D01*
G02X394143Y-56983I1178J1178D01*
G01Y-48541D01*
G02X395421Y-46464I2327J0D01*
G01X354174Y-63909D02*
Y-59372D01*
G02X354660Y-58197I1663J0D01*
G01X354661Y-58196D01*
G03X355149Y-57020I-1176J1177D01*
G01Y-53448D01*
G03X354421Y-51690I-2486J0D01*
G01X352862Y-50131D01*
G02X352070Y-48217I1915J1913D01*
G01Y-47641D01*
G03X350893Y-46464I-1177J0D01*
G01X350621D01*
G01X363622Y-63909D02*
Y-59372D01*
G02X364108Y-58197I1663J0D01*
G01X364109Y-58196D01*
G03X364597Y-57020I-1176J1177D01*
G01Y-53327D01*
X364596Y-53328D01*
G03X363421Y-50490I-4013J1D01*
G01X363062Y-50131D01*
G02X362270Y-48217I1915J1913D01*
G01Y-47641D01*
G03X361093Y-46464I-1177J0D01*
G01X360821D01*
G01X371021D02*
X371293D01*
G02X372470Y-47641I0J-1177D01*
G01Y-48541D01*
G02X372476Y-49014I-1976J-262D01*
G03X373366Y-51831I3666J-391D01*
G02X374046Y-53641I-2071J-1811D01*
G01Y-57020D01*
G02X373558Y-58196I-1664J1D01*
G01X373557Y-58197D01*
G03X373071Y-59372I1177J-1175D01*
G01Y-63909D01*
G01X381221Y-46464D02*
X381493D01*
G02X382670Y-47641I0J-1177D01*
G01Y-49318D01*
G03X382697Y-49572I1179J-3D01*
G02X383495Y-56983I-34031J-7413D01*
G01Y-57020D01*
G02X383007Y-58196I-1664J1D01*
G01X383006Y-58197D01*
G03X382520Y-59372I1177J-1175D01*
G01Y-63909D01*
G01X391969D02*
Y-59372D01*
G02X392455Y-58197I1663J0D01*
G01X392456Y-58196D01*
G03X392944Y-57020I-1176J1177D01*
G01Y-56983D01*
X392943D01*
Y-48541D01*
G03X391421Y-46464I-2178J0D01*
G01X469902Y-64309D02*
Y-60492D01*
G03X469414Y-59314I-1666J0D01*
G02X468927Y-58138I1176J1176D01*
G03Y-58134I-2866J2D01*
G01X469057Y-56404D01*
X469218Y-54619D01*
X469255Y-54430D01*
X469347Y-53962D01*
X492584Y66037D01*
Y66117D01*
X476545Y157081D01*
X470643Y165508D01*
X459901Y173030D01*
X390671Y185238D01*
X362121Y205229D01*
X360993Y206019D01*
X360907Y206079D01*
X359577Y207978D01*
X359274Y209700D01*
Y210900D01*
G03X358972Y212608I-4978J1D01*
G03X358312Y213841I-4675J-1709D01*
G03X357816Y214420I-4017J-2939D01*
G01X357382Y214637D01*
X357369Y214644D01*
X357368D01*
G02X357297Y214686I219J450D01*
G02X357274Y214704I297J403D01*
G02X357145Y215315I318J386D01*
G01X358623Y218269D01*
G01X354683Y210394D02*
X355945Y212917D01*
G02X356388Y213418I1164J-583D01*
G02X357344Y213132I0J-1741D01*
G02X357844Y212196I-3049J-2230D01*
G02X358074Y210899I-3548J-1298D01*
G01Y209595D01*
X358441Y207508D01*
X360045Y205217D01*
X390201Y184102D01*
X459431Y171894D01*
X469781Y164646D01*
X475409Y156611D01*
X491365Y66117D01*
X491375Y66107D01*
X471098Y-38606D01*
X470289Y-39152D01*
X470004Y-40625D01*
X470550Y-41433D01*
X470265Y-42906D01*
X469457Y-43452D01*
X469172Y-44925D01*
X469718Y-45733D01*
X469433Y-47206D01*
X468624Y-47752D01*
X468339Y-49225D01*
X468885Y-50033D01*
X468600Y-51506D01*
X468028Y-54450D01*
X467861Y-56305D01*
X467727Y-58083D01*
G02X467239Y-59261I-1666J0D01*
G03X466752Y-60437I1176J-1176D01*
G01Y-64309D01*
G01X374368Y218269D02*
X372892Y215314D01*
G03X373116Y214643I448J-223D01*
G01X373117D01*
X373563Y214421D01*
G02X374983Y210993I-3428J-3428D01*
G01Y209732D01*
X375200Y208500D01*
X377325Y205464D01*
X401919Y188244D01*
X411603Y186537D01*
X415366Y185873D01*
X461859Y177673D01*
X461858D01*
X473840Y169281D01*
X481103Y158910D01*
X497574Y65494D01*
Y65493D01*
X497565Y65484D01*
Y64880D01*
X479398Y-51315D01*
X478375Y-57131D01*
Y-57862D01*
X478381Y-57931D01*
G03X478863Y-58963I1657J145D01*
G02X479350Y-60139I-1176J-1176D01*
G01Y-64309D01*
G01X488799D02*
Y-60189D01*
G03X488312Y-59013I-1663J0D01*
G02X487825Y-57837I1176J1176D01*
G03Y-57803I-2825J17D01*
G01X488116Y-56150D01*
X502384Y65322D01*
X485560Y160705D01*
X476083Y174240D01*
X464775Y182158D01*
X411511Y191549D01*
X396300Y202200D01*
X392737Y204695D01*
X391800Y206600D01*
G02X390800Y210900I8745J4300D01*
G03X389473Y214257I-4911J0D01*
G03X389362Y214372I-3588J-3353D01*
G01X389313Y214421D01*
X388867Y214643D01*
X388866D01*
G02X388642Y215314I224J448D01*
G01X390118Y218269D01*
G01X498248Y-64309D02*
Y-60338D01*
G03X497760Y-59160I-1666J0D01*
G02X497273Y-57984I1176J1176D01*
G01X497396Y-55700D01*
X507447Y63968D01*
X507451Y63972D01*
Y63973D01*
X489717Y164523D01*
X481400Y176400D01*
X466063Y187139D01*
X423681Y194611D01*
X408387Y205321D01*
X407086Y207180D01*
X406721Y209248D01*
Y210523D01*
G03X405212Y214268I-5401J0D01*
G03X405139Y214342I-3881J-3756D01*
G01X405100Y214381D01*
G03X405012Y214445I-242J-240D01*
G01X404614Y214644D01*
X404613D01*
G02X404390Y215315I224J447D01*
G01X405868Y218269D01*
G01X421613D02*
X420137Y215314D01*
G03X420361Y214643I448J-223D01*
G01X420362D01*
X420808Y214421D01*
G02X422233Y210981I-3440J-3440D01*
G01Y209348D01*
X422400Y208400D01*
X423826Y206363D01*
X436023Y197822D01*
X456000Y194300D01*
X468968Y192013D01*
X485519Y180426D01*
X494064Y168223D01*
X495085Y164093D01*
X512600Y63500D01*
X506816Y-55691D01*
X506659Y-56582D01*
X506722Y-57582D01*
G03X507209Y-58758I1663J0D01*
G02X507697Y-59936I-1178J-1178D01*
G01Y-64309D01*
G01X370433Y210394D02*
X371907Y213346D01*
G02X372578Y213570I447J-223D01*
G01X372579D01*
X372588Y213565D01*
X372840Y213440D01*
G02X373783Y210992I-2705J-2448D01*
G01Y209627D01*
X374064Y208030D01*
X376463Y204602D01*
X401449Y187108D01*
X411394Y185355D01*
X461388Y176537D01*
X472978Y168419D01*
X479967Y158440D01*
X496355Y65494D01*
X496365Y65484D01*
Y64974D01*
X479566Y-42467D01*
X478778Y-43042D01*
X478546Y-44524D01*
X479121Y-45313D01*
X478890Y-46795D01*
X478101Y-47370D01*
X477870Y-48852D01*
X478445Y-49640D01*
X478213Y-51122D01*
X477175Y-57026D01*
Y-58036D01*
G02X476688Y-59212I-1663J0D01*
G03X476201Y-60388I1176J-1176D01*
G01Y-64309D01*
G01X485650D02*
Y-60139D01*
G02X486138Y-58963I1664J-1D01*
G01X486151Y-58950D01*
G03X486625Y-57803I-1151J1147D01*
G01X486643Y-57595D01*
X486928Y-55976D01*
X487244Y-53289D01*
X486639Y-52523D01*
X486814Y-51034D01*
X487580Y-50429D01*
X487755Y-48939D01*
X487150Y-48173D01*
X487325Y-46684D01*
X488090Y-46079D01*
X501171Y65287D01*
X484424Y160235D01*
X475221Y173378D01*
X464305Y181022D01*
X411041Y190413D01*
X395611Y201217D01*
X391795Y203888D01*
X390723Y206070D01*
G02X389599Y210900I9822J4831D01*
G03X388597Y213436I-3710J0D01*
G01X388329Y213570D01*
X388328D01*
G03X387657Y213346I-224J-447D01*
G01X386183Y210394D01*
G01X401928D02*
X403406Y213347D01*
G02X404077Y213570I447J-224D01*
G01X404078D01*
X404343Y213437D01*
X404346Y213435D01*
G02X405521Y210523I-3025J-2914D01*
G01Y209142D01*
X405950Y206710D01*
X407525Y204459D01*
X423211Y193475D01*
X465592Y186003D01*
X465593D01*
X480538Y175538D01*
X488581Y164053D01*
X506232Y63973D01*
X506242Y63963D01*
X497037Y-45635D01*
X496292Y-46265D01*
X496166Y-47760D01*
X496796Y-48505D01*
X496670Y-50000D01*
X495925Y-50630D01*
X495799Y-52124D01*
X496429Y-52870D01*
X496200Y-55600D01*
X496073Y-57837D01*
G02X495585Y-59015I-1666J0D01*
G03X495098Y-60191I1176J-1176D01*
G01Y-64309D01*
G01X417678Y210394D02*
X419152Y213346D01*
G02X419823Y213570I447J-223D01*
G01X419824D01*
X419833Y213565D01*
X420085Y213440D01*
G02X421033Y210980I-2717J-2460D01*
G01Y209243D01*
X421264Y207930D01*
X422964Y205501D01*
X435553Y196686D01*
X455792Y193118D01*
X468498Y190877D01*
X484657Y179564D01*
X492952Y167718D01*
X493909Y163846D01*
X511394Y63425D01*
X506169Y-44265D01*
X505446Y-44921D01*
X505374Y-46419D01*
X506029Y-47142D01*
X505957Y-48640D01*
X505234Y-49296D01*
X505161Y-50794D01*
X505817Y-51517D01*
X505621Y-55557D01*
X505452Y-56513D01*
X505516Y-57653D01*
Y-57730D01*
X505526D01*
Y-57735D01*
X505522Y-57736D01*
Y-57741D01*
G02X505036Y-58916I-1663J0D01*
G01X505035Y-58917D01*
G03X504547Y-60093I1176J-1177D01*
G01Y-64309D01*
G01X437363Y218269D02*
X435885Y215316D01*
G03X436108Y214645I447J-224D01*
G01X436109D01*
Y214646D01*
X436558Y214421D01*
G02X437594Y212928I-849J-1695D01*
G03X438448Y208750I22353J2393D01*
G01X438829Y207502D01*
X438830Y207499D01*
X438826Y207487D01*
X439573Y205959D01*
X442034Y204235D01*
X446046Y201425D01*
X471320Y196969D01*
X489562Y184196D01*
X498614Y171268D01*
X517495Y64195D01*
Y64191D01*
X517500Y64192D01*
Y64188D01*
X517501D01*
X517608Y63586D01*
X516300Y-54413D01*
X516272Y-55214D01*
X516171Y-57965D01*
G02Y-57982I-2866J-9D01*
G03X516658Y-59158I1663J0D01*
G02X517146Y-60336I-1178J-1178D01*
G01Y-64309D01*
G01X513996D02*
Y-60293D01*
G02X514483Y-59117I1663J0D01*
G03X514971Y-57940I-1178J1178D01*
G01X515100Y-54400D01*
X515119Y-52660D01*
X514437Y-51962D01*
X514454Y-50462D01*
X515151Y-49780D01*
X515168Y-48280D01*
X514486Y-47582D01*
X514502Y-46082D01*
X515200Y-45400D01*
X515212Y-44193D01*
X515213D01*
X515826Y11172D01*
X516381Y61302D01*
X516406Y63486D01*
X516318Y63979D01*
Y63983D01*
X516321Y63984D01*
Y63988D01*
X516311Y63998D01*
X497478Y170798D01*
X488700Y183334D01*
X470850Y195833D01*
X445576Y200289D01*
X441345Y203252D01*
X438630Y205153D01*
X437747Y206961D01*
X437739Y206963D01*
X437737Y206966D01*
X437300Y208399D01*
G02X436400Y212800I22646J6924D01*
G03X436020Y213347I-691J-74D01*
G01X435573Y213571D01*
X435572D01*
G03X434901Y213348I-224J-447D01*
G01X433423Y210394D01*
G54D59*
X414719Y63934D03*
Y48186D03*
X437719D03*
Y63934D03*
G54D68*
X515814Y178749D03*
X528026D03*
X515814Y184655D03*
Y182686D03*
Y180718D03*
X528026D03*
Y182686D03*
Y184655D03*
G54D78*
G01X-65001Y-234972D02*
Y-217472D01*
X-60635D01*
X-58888Y-218347D01*
X-57578Y-219514D01*
X-56486Y-221263D01*
X-55613Y-223306D01*
X-55395Y-226222D01*
X-55613Y-229139D01*
X-56486Y-231181D01*
X-57578Y-232931D01*
X-58888Y-234097D01*
X-60635Y-234972D01*
X-65001D01*
G01X-48157Y-217472D02*
X-42698Y-234972D01*
X-37239Y-217472D01*
G01X-25198D02*
Y-234972D01*
G01X-30220Y-217472D02*
X-20176D01*
G01X5435Y-234972D02*
Y-217472D01*
X10894D01*
X12640Y-218347D01*
X13732Y-219514D01*
X14169Y-221847D01*
X13732Y-224181D01*
X12422Y-225639D01*
X10894Y-226514D01*
X5435D01*
G01X10894D02*
X14169Y-234972D01*
G01X27302Y-223306D02*
Y-234972D01*
G01Y-218639D02*
X26865Y-218347D01*
Y-217764D01*
X27302Y-217472D01*
X27739Y-217764D01*
Y-218347D01*
X27302Y-218639D01*
G01X41527Y-232931D02*
X42619Y-234097D01*
X44147Y-234972D01*
X45457D01*
X46767Y-234389D01*
X47640Y-233514D01*
X48077Y-232348D01*
X47859Y-230597D01*
X46985Y-229722D01*
X43055Y-227972D01*
X42182Y-225930D01*
X42619Y-224472D01*
X43492Y-223597D01*
X44802Y-223306D01*
X46112Y-223597D01*
X47422Y-224472D01*
G01X59027Y-227097D02*
X66014D01*
X65359Y-225055D01*
X64267Y-223889D01*
X62739Y-223306D01*
X61210Y-223597D01*
X59900Y-224472D01*
X59027Y-226514D01*
X58590Y-228264D01*
Y-230014D01*
X59027Y-231764D01*
X60119Y-233514D01*
X61429Y-234680D01*
X62957Y-234972D01*
X64485Y-234389D01*
X66014Y-232639D01*
G01X76745Y-234972D02*
Y-223306D01*
G01Y-225639D02*
X77837Y-224472D01*
X78929Y-223597D01*
X80457Y-223306D01*
X81548Y-223597D01*
X82859Y-224472D01*
G01X119605Y-218931D02*
X118295Y-218055D01*
X116767Y-217472D01*
X115020D01*
X113055Y-218347D01*
X111527Y-219805D01*
X110435Y-221556D01*
X109562Y-224472D01*
X109343Y-227097D01*
X109780Y-229722D01*
X110435Y-231472D01*
X111745Y-233222D01*
X113274Y-234389D01*
X114802Y-234972D01*
X116330D01*
X117859Y-234389D01*
X119169Y-233514D01*
X120261Y-232348D01*
G01X136232Y-234972D02*
Y-223306D01*
G01Y-225347D02*
X135359Y-224181D01*
X134048Y-223597D01*
X132520Y-223306D01*
X130992Y-223889D01*
X129682Y-225055D01*
X128808Y-226805D01*
X128372Y-229139D01*
X128808Y-231472D01*
X129682Y-233222D01*
X130992Y-234389D01*
X132520Y-234972D01*
X134048Y-234680D01*
X135359Y-233806D01*
X136232Y-232639D01*
G01X146745Y-234972D02*
Y-223306D01*
G01Y-225639D02*
X147837Y-224472D01*
X148929Y-223597D01*
X150457Y-223306D01*
X151548Y-223597D01*
X152859Y-224472D01*
G01X171232Y-217472D02*
Y-234972D01*
G01Y-232348D02*
X170359Y-233806D01*
X169048Y-234680D01*
X167520Y-234972D01*
X165774Y-234389D01*
X164464Y-232931D01*
X163590Y-231181D01*
X163372Y-229139D01*
X163590Y-227097D01*
X164464Y-225347D01*
X165774Y-223889D01*
X167520Y-223306D01*
X169048Y-223597D01*
X170140Y-224181D01*
X171232Y-225347D01*
G01X178252Y-240805D02*
X191352D01*
G01X197717Y-232639D02*
X199464Y-234097D01*
X201429Y-234972D01*
X203175D01*
X204922Y-234097D01*
X206232Y-232639D01*
X206887Y-230597D01*
X206450Y-228556D01*
X205359Y-226805D01*
X203394Y-225639D01*
X200774Y-225055D01*
X199245Y-223889D01*
X198590Y-221847D01*
X199027Y-219805D01*
X200119Y-218347D01*
X201647Y-217472D01*
X203175D01*
X204704Y-218055D01*
X206014Y-219514D01*
G01X215217Y-232639D02*
X216964Y-234097D01*
X218929Y-234972D01*
X220675D01*
X222422Y-234097D01*
X223732Y-232639D01*
X224387Y-230597D01*
X223950Y-228556D01*
X222859Y-226805D01*
X220894Y-225639D01*
X218274Y-225055D01*
X216745Y-223889D01*
X216090Y-221847D01*
X216527Y-219805D01*
X217619Y-218347D01*
X219147Y-217472D01*
X220675D01*
X222204Y-218055D01*
X223514Y-219514D01*
G01X250654Y-220389D02*
X251964Y-218639D01*
X253492Y-217764D01*
X255239Y-217472D01*
X257422Y-218055D01*
X258950Y-219514D01*
X259387Y-221263D01*
X259169Y-223014D01*
X258295Y-224472D01*
X253929Y-227389D01*
X251964Y-229430D01*
X250654Y-232348D01*
X250217Y-234972D01*
X259387D01*
G01X286527Y-232931D02*
X287619Y-234097D01*
X289147Y-234972D01*
X290457D01*
X291767Y-234389D01*
X292640Y-233514D01*
X293077Y-232348D01*
X292859Y-230597D01*
X291985Y-229722D01*
X288055Y-227972D01*
X287182Y-225930D01*
X287619Y-224472D01*
X288492Y-223597D01*
X289802Y-223306D01*
X291112Y-223597D01*
X292422Y-224472D01*
G01X307302Y-234972D02*
Y-217472D01*
G01X324802Y-234972D02*
X323492Y-234680D01*
X322182Y-233514D01*
X321308Y-231472D01*
X320872Y-229139D01*
X321308Y-226805D01*
X322182Y-224764D01*
X323492Y-223597D01*
X324802Y-223306D01*
X326112Y-223597D01*
X327422Y-224764D01*
X328295Y-226805D01*
X328514Y-229139D01*
X328295Y-231472D01*
X327422Y-233514D01*
X326112Y-234680D01*
X324802Y-234972D01*
G01X342302Y-217472D02*
Y-234972D01*
G01X339245Y-223306D02*
X345359D01*
G01X356527Y-232931D02*
X357619Y-234097D01*
X359147Y-234972D01*
X360457D01*
X361767Y-234389D01*
X362640Y-233514D01*
X363077Y-232348D01*
X362859Y-230597D01*
X361985Y-229722D01*
X358055Y-227972D01*
X357182Y-225930D01*
X357619Y-224472D01*
X358492Y-223597D01*
X359802Y-223306D01*
X361112Y-223597D01*
X362422Y-224472D01*
G01X109125Y-189972D02*
Y-172472D01*
X114802Y-187055D01*
X120479Y-172472D01*
Y-189972D01*
G01X132302D02*
X130992Y-189680D01*
X129682Y-188514D01*
X128808Y-186472D01*
X128372Y-184139D01*
X128808Y-181805D01*
X129682Y-179764D01*
X130992Y-178597D01*
X132302Y-178306D01*
X133612Y-178597D01*
X134922Y-179764D01*
X135795Y-181805D01*
X136014Y-184139D01*
X135795Y-186472D01*
X134922Y-188514D01*
X133612Y-189680D01*
X132302Y-189972D01*
G01X153732Y-172472D02*
Y-189972D01*
G01Y-187348D02*
X152859Y-188806D01*
X151548Y-189680D01*
X150020Y-189972D01*
X148274Y-189389D01*
X146964Y-187931D01*
X146090Y-186181D01*
X145872Y-184139D01*
X146090Y-182097D01*
X146964Y-180347D01*
X148274Y-178889D01*
X150020Y-178306D01*
X151548Y-178597D01*
X152640Y-179181D01*
X153732Y-180347D01*
G01X164027Y-182097D02*
X171014D01*
X170359Y-180055D01*
X169267Y-178889D01*
X167739Y-178306D01*
X166210Y-178597D01*
X164900Y-179472D01*
X164027Y-181514D01*
X163590Y-183264D01*
Y-185014D01*
X164027Y-186764D01*
X165119Y-188514D01*
X166429Y-189680D01*
X167957Y-189972D01*
X169485Y-189389D01*
X171014Y-187639D01*
G01X184802Y-189972D02*
Y-172472D01*
G01X418602Y-234972D02*
Y-217472D01*
X415982Y-220972D01*
G01Y-234972D02*
X421222D01*
G01X431299Y-232348D02*
X432608Y-233806D01*
X434137Y-234680D01*
X436102Y-234972D01*
X438067Y-234389D01*
X439595Y-233222D01*
X440687Y-231181D01*
X440905Y-228847D01*
X440469Y-226514D01*
X439377Y-225055D01*
X437848Y-223889D01*
X436320Y-223597D01*
X434792Y-223889D01*
X432827Y-225055D01*
X433482Y-217472D01*
X439377D01*
G01X449890Y-232931D02*
X451419Y-234389D01*
X453165Y-234972D01*
X454912Y-234389D01*
X456440Y-232639D01*
X457532Y-230014D01*
X457969Y-227389D01*
Y-224181D01*
X457532Y-221556D01*
X456440Y-219222D01*
X455130Y-218055D01*
X453602Y-217472D01*
X451855Y-218055D01*
X450545Y-219222D01*
X449672Y-220972D01*
X449235Y-223306D01*
X449672Y-225347D01*
X450764Y-227389D01*
X452074Y-228556D01*
X453602Y-228847D01*
X455348Y-228264D01*
X456659Y-226805D01*
X457969Y-224181D01*
G01X466954Y-227681D02*
X468482Y-225639D01*
X469792Y-224472D01*
X471539Y-223889D01*
X473067Y-224472D01*
X474159Y-225639D01*
X475032Y-227389D01*
X475250Y-229430D01*
X475032Y-231181D01*
X474159Y-232931D01*
X472848Y-234389D01*
X471320Y-234972D01*
X469574Y-234389D01*
X468045Y-232639D01*
X467172Y-230014D01*
X466954Y-227097D01*
X467390Y-223306D01*
X468045Y-221263D01*
X469137Y-219222D01*
X470665Y-217764D01*
X472194Y-217472D01*
X473722Y-218055D01*
X474814Y-219514D01*
G01X488602Y-234972D02*
X490130Y-234680D01*
X491877Y-233806D01*
X492969Y-232348D01*
X493405Y-230305D01*
X492969Y-228264D01*
X491659Y-226514D01*
X489694Y-225639D01*
X487510D01*
X486200Y-225055D01*
X485108Y-223597D01*
X484672Y-221556D01*
X485327Y-219514D01*
X486855Y-218055D01*
X488602Y-217472D01*
X490348Y-218055D01*
X491877Y-219514D01*
X492532Y-221556D01*
X492095Y-223597D01*
X491004Y-225055D01*
X489694Y-225639D01*
X487510D01*
X485545Y-226514D01*
X484235Y-228264D01*
X483799Y-230305D01*
X484235Y-232348D01*
X485327Y-233806D01*
X487074Y-234680D01*
X488602Y-234972D01*
G01X405485Y-189972D02*
Y-172472D01*
X410725D01*
X412472Y-173347D01*
X413782Y-175389D01*
X414219Y-177722D01*
X413782Y-180055D01*
X412690Y-181805D01*
X410725Y-182681D01*
X405485D01*
G01X432155Y-173931D02*
X430845Y-173055D01*
X429317Y-172472D01*
X427570D01*
X425605Y-173347D01*
X424077Y-174805D01*
X422985Y-176556D01*
X422112Y-179472D01*
X421893Y-182097D01*
X422330Y-184722D01*
X422985Y-186472D01*
X424295Y-188222D01*
X425824Y-189389D01*
X427352Y-189972D01*
X428880D01*
X430409Y-189389D01*
X431719Y-188514D01*
X432811Y-187348D01*
G01X446598Y-180639D02*
X447472Y-179764D01*
X448127Y-178306D01*
X448564Y-176263D01*
X448127Y-174514D01*
X447254Y-173347D01*
X445725Y-172472D01*
X439830D01*
Y-189972D01*
X447035D01*
X448564Y-188806D01*
X449437Y-187055D01*
X449874Y-185014D01*
X449437Y-182972D01*
X448127Y-181222D01*
X446598Y-180639D01*
X439830D01*
G01X455802Y-195805D02*
X468902D01*
G01X474830Y-189972D02*
Y-172472D01*
X484874Y-189972D01*
Y-172472D01*
G01X497352Y-189972D02*
X495605Y-189680D01*
X494077Y-188514D01*
X492767Y-186764D01*
X491893Y-184722D01*
X491457Y-182389D01*
Y-180055D01*
X491893Y-177722D01*
X492767Y-175680D01*
X494077Y-173931D01*
X495605Y-172764D01*
X497352Y-172472D01*
X499098Y-172764D01*
X500627Y-173931D01*
X501937Y-175680D01*
X502811Y-177722D01*
X503247Y-180055D01*
Y-182389D01*
X502811Y-184722D01*
X501937Y-186764D01*
X500627Y-188514D01*
X499098Y-189680D01*
X497352Y-189972D01*
G01X571152Y-234972D02*
Y-217472D01*
X568532Y-220972D01*
G01Y-234972D02*
X573772D01*
G01X583193D02*
X588652Y-217472D01*
X594111Y-234972D01*
G01X592145Y-228847D02*
X585158D01*
G01X548193Y-172472D02*
X553652Y-189972D01*
X559111Y-172472D01*
G01X575519Y-189972D02*
X566785D01*
Y-172472D01*
X575519D01*
G01X572025Y-180930D02*
X566785D01*
G01X584285Y-189972D02*
Y-172472D01*
X589744D01*
X591490Y-173347D01*
X592582Y-174514D01*
X593019Y-176847D01*
X592582Y-179181D01*
X591272Y-180639D01*
X589744Y-181514D01*
X584285D01*
G01X589744D02*
X593019Y-189972D01*
G01X606152Y-190555D02*
X605715Y-190264D01*
Y-189680D01*
X606152Y-189389D01*
X606589Y-189680D01*
Y-190264D01*
X606152Y-190555D01*
G01X707985Y-217472D02*
Y-234972D01*
X716719D01*
G01X729852D02*
Y-217472D01*
X727232Y-220972D01*
G01Y-234972D02*
X732472D01*
G01X681735Y-172472D02*
Y-189972D01*
X690469D01*
G01X707532D02*
Y-178306D01*
G01Y-180347D02*
X706659Y-179181D01*
X705348Y-178597D01*
X703820Y-178306D01*
X702292Y-178889D01*
X700982Y-180055D01*
X700108Y-181805D01*
X699672Y-184139D01*
X700108Y-186472D01*
X700982Y-188222D01*
X702292Y-189389D01*
X703820Y-189972D01*
X705348Y-189680D01*
X706659Y-188806D01*
X707532Y-187639D01*
G01X716517Y-195222D02*
X717827Y-195805D01*
X719574Y-195222D01*
X720665Y-194056D01*
X721539Y-192597D01*
X722848Y-187931D01*
X725687Y-178306D01*
G01X718700D02*
X722848Y-187931D01*
G01X735327Y-182097D02*
X742314D01*
X741659Y-180055D01*
X740567Y-178889D01*
X739039Y-178306D01*
X737510Y-178597D01*
X736200Y-179472D01*
X735327Y-181514D01*
X734890Y-183264D01*
Y-185014D01*
X735327Y-186764D01*
X736419Y-188514D01*
X737729Y-189680D01*
X739257Y-189972D01*
X740785Y-189389D01*
X742314Y-187639D01*
G01X753045Y-189972D02*
Y-178306D01*
G01Y-180639D02*
X754137Y-179472D01*
X755229Y-178597D01*
X756757Y-178306D01*
X757848Y-178597D01*
X759159Y-179472D01*
G01X824705Y-218931D02*
X823395Y-218055D01*
X821867Y-217472D01*
X820120D01*
X818155Y-218347D01*
X816627Y-219805D01*
X815535Y-221556D01*
X814662Y-224472D01*
X814443Y-227097D01*
X814880Y-229722D01*
X815535Y-231472D01*
X816845Y-233222D01*
X818374Y-234389D01*
X819902Y-234972D01*
X821430D01*
X822959Y-234389D01*
X824269Y-233514D01*
X825361Y-232348D01*
G01X837402Y-234972D02*
X835655Y-234680D01*
X834127Y-233514D01*
X832817Y-231764D01*
X831943Y-229722D01*
X831507Y-227389D01*
Y-225055D01*
X831943Y-222722D01*
X832817Y-220680D01*
X834127Y-218931D01*
X835655Y-217764D01*
X837402Y-217472D01*
X839148Y-217764D01*
X840677Y-218931D01*
X841987Y-220680D01*
X842861Y-222722D01*
X843297Y-225055D01*
Y-227389D01*
X842861Y-229722D01*
X841987Y-231764D01*
X840677Y-233514D01*
X839148Y-234680D01*
X837402Y-234972D01*
G01X849880D02*
Y-217472D01*
X859924Y-234972D01*
Y-217472D01*
G01X867380Y-234972D02*
Y-217472D01*
X877424Y-234972D01*
Y-217472D01*
G01X887282D02*
X892522D01*
G01X889902D02*
Y-234972D01*
G01X887282D02*
X892522D01*
G01X911769D02*
X903035D01*
Y-217472D01*
X911769D01*
G01X908275Y-225930D02*
X903035D01*
G01X937817Y-234972D02*
X946987Y-217472D01*
G01X937817D02*
X946987Y-234972D01*
G01X955317D02*
Y-217472D01*
G01X964487D02*
Y-234972D01*
G01Y-226222D02*
X955317D01*
G01X823849Y-189972D02*
Y-172472D01*
X828215D01*
X829962Y-173347D01*
X831272Y-174514D01*
X832364Y-176263D01*
X833237Y-178306D01*
X833455Y-181222D01*
X833237Y-184139D01*
X832364Y-186181D01*
X831272Y-187931D01*
X829962Y-189097D01*
X828215Y-189972D01*
X823849D01*
G01X842877Y-182097D02*
X849864D01*
X849209Y-180055D01*
X848117Y-178889D01*
X846589Y-178306D01*
X845060Y-178597D01*
X843750Y-179472D01*
X842877Y-181514D01*
X842440Y-183264D01*
Y-185014D01*
X842877Y-186764D01*
X843969Y-188514D01*
X845279Y-189680D01*
X846807Y-189972D01*
X848335Y-189389D01*
X849864Y-187639D01*
G01X860377Y-187931D02*
X861469Y-189097D01*
X862997Y-189972D01*
X864307D01*
X865617Y-189389D01*
X866490Y-188514D01*
X866927Y-187348D01*
X866709Y-185597D01*
X865835Y-184722D01*
X861905Y-182972D01*
X861032Y-180930D01*
X861469Y-179472D01*
X862342Y-178597D01*
X863652Y-178306D01*
X864962Y-178597D01*
X866272Y-179472D01*
G01X881152Y-178306D02*
Y-189972D01*
G01Y-173639D02*
X880715Y-173347D01*
Y-172764D01*
X881152Y-172472D01*
X881589Y-172764D01*
Y-173347D01*
X881152Y-173639D01*
G01X895595Y-194347D02*
X897124Y-195514D01*
X898870Y-195805D01*
X900398Y-195514D01*
X901709Y-194056D01*
X902582Y-192014D01*
Y-178306D01*
G01Y-180639D02*
X901709Y-179472D01*
X900398Y-178597D01*
X898870Y-178306D01*
X897124Y-178889D01*
X896032Y-180055D01*
X895158Y-182097D01*
X894722Y-184139D01*
X894940Y-185889D01*
X895814Y-187931D01*
X897124Y-189389D01*
X898870Y-189972D01*
X900180Y-189680D01*
X901709Y-188514D01*
X902582Y-187348D01*
G01X912440Y-189972D02*
Y-178306D01*
G01Y-181222D02*
X913314Y-179764D01*
X914624Y-178597D01*
X916370Y-178306D01*
X917898Y-178597D01*
X919209Y-179764D01*
X919864Y-181805D01*
Y-189972D01*
G01X930377Y-182097D02*
X937364D01*
X936709Y-180055D01*
X935617Y-178889D01*
X934089Y-178306D01*
X932560Y-178597D01*
X931250Y-179472D01*
X930377Y-181514D01*
X929940Y-183264D01*
Y-185014D01*
X930377Y-186764D01*
X931469Y-188514D01*
X932779Y-189680D01*
X934307Y-189972D01*
X935835Y-189389D01*
X937364Y-187639D01*
G01X948095Y-189972D02*
Y-178306D01*
G01Y-180639D02*
X949187Y-179472D01*
X950279Y-178597D01*
X951807Y-178306D01*
X952898Y-178597D01*
X954209Y-179472D01*
G01X994852Y-217472D02*
X993105Y-218055D01*
X991795Y-219514D01*
X990922Y-221263D01*
X990267Y-223597D01*
X990049Y-226222D01*
X990267Y-228847D01*
X990922Y-231181D01*
X991795Y-232931D01*
X993105Y-234389D01*
X994852Y-234972D01*
X996598Y-234389D01*
X997909Y-232931D01*
X998782Y-231181D01*
X999437Y-228847D01*
X999655Y-226222D01*
X999437Y-223597D01*
X998782Y-221263D01*
X997909Y-219514D01*
X996598Y-218055D01*
X994852Y-217472D01*
G01X1012352Y-234972D02*
X1013880Y-234680D01*
X1015627Y-233806D01*
X1016719Y-232348D01*
X1017155Y-230305D01*
X1016719Y-228264D01*
X1015409Y-226514D01*
X1013444Y-225639D01*
X1011260D01*
X1009950Y-225055D01*
X1008858Y-223597D01*
X1008422Y-221556D01*
X1009077Y-219514D01*
X1010605Y-218055D01*
X1012352Y-217472D01*
X1014098Y-218055D01*
X1015627Y-219514D01*
X1016282Y-221556D01*
X1015845Y-223597D01*
X1014754Y-225055D01*
X1013444Y-225639D01*
X1011260D01*
X1009295Y-226514D01*
X1007985Y-228264D01*
X1007549Y-230305D01*
X1007985Y-232348D01*
X1009077Y-233806D01*
X1010824Y-234680D01*
X1012352Y-234972D01*
G01X1025922Y-235555D02*
X1033782Y-217472D01*
G01X1043204Y-220389D02*
X1044514Y-218639D01*
X1046042Y-217764D01*
X1047789Y-217472D01*
X1049972Y-218055D01*
X1051500Y-219514D01*
X1051937Y-221263D01*
X1051719Y-223014D01*
X1050845Y-224472D01*
X1046479Y-227389D01*
X1044514Y-229430D01*
X1043204Y-232348D01*
X1042767Y-234972D01*
X1051937D01*
G01X1060049Y-232348D02*
X1061358Y-233806D01*
X1062887Y-234680D01*
X1064852Y-234972D01*
X1066817Y-234389D01*
X1068345Y-233222D01*
X1069437Y-231181D01*
X1069655Y-228847D01*
X1069219Y-226514D01*
X1068127Y-225055D01*
X1066598Y-223889D01*
X1065070Y-223597D01*
X1063542Y-223889D01*
X1061577Y-225055D01*
X1062232Y-217472D01*
X1068127D01*
G01X1078422Y-235555D02*
X1086282Y-217472D01*
G01X1095704Y-220389D02*
X1097014Y-218639D01*
X1098542Y-217764D01*
X1100289Y-217472D01*
X1102472Y-218055D01*
X1104000Y-219514D01*
X1104437Y-221263D01*
X1104219Y-223014D01*
X1103345Y-224472D01*
X1098979Y-227389D01*
X1097014Y-229430D01*
X1095704Y-232348D01*
X1095267Y-234972D01*
X1104437D01*
G01X1117352Y-217472D02*
X1115605Y-218055D01*
X1114295Y-219514D01*
X1113422Y-221263D01*
X1112767Y-223597D01*
X1112549Y-226222D01*
X1112767Y-228847D01*
X1113422Y-231181D01*
X1114295Y-232931D01*
X1115605Y-234389D01*
X1117352Y-234972D01*
X1119098Y-234389D01*
X1120409Y-232931D01*
X1121282Y-231181D01*
X1121937Y-228847D01*
X1122155Y-226222D01*
X1121937Y-223597D01*
X1121282Y-221263D01*
X1120409Y-219514D01*
X1119098Y-218055D01*
X1117352Y-217472D01*
G01X1134852Y-234972D02*
Y-217472D01*
X1132232Y-220972D01*
G01Y-234972D02*
X1137472D01*
G01X1148204Y-227681D02*
X1149732Y-225639D01*
X1151042Y-224472D01*
X1152789Y-223889D01*
X1154317Y-224472D01*
X1155409Y-225639D01*
X1156282Y-227389D01*
X1156500Y-229430D01*
X1156282Y-231181D01*
X1155409Y-232931D01*
X1154098Y-234389D01*
X1152570Y-234972D01*
X1150824Y-234389D01*
X1149295Y-232639D01*
X1148422Y-230014D01*
X1148204Y-227097D01*
X1148640Y-223306D01*
X1149295Y-221263D01*
X1150387Y-219222D01*
X1151915Y-217764D01*
X1153444Y-217472D01*
X1154972Y-218055D01*
X1156064Y-219514D01*
G01X1042549Y-189972D02*
Y-172472D01*
X1046915D01*
X1048662Y-173347D01*
X1049972Y-174514D01*
X1051064Y-176263D01*
X1051937Y-178306D01*
X1052155Y-181222D01*
X1051937Y-184139D01*
X1051064Y-186181D01*
X1049972Y-187931D01*
X1048662Y-189097D01*
X1046915Y-189972D01*
X1042549D01*
G01X1068782D02*
Y-178306D01*
G01Y-180347D02*
X1067909Y-179181D01*
X1066598Y-178597D01*
X1065070Y-178306D01*
X1063542Y-178889D01*
X1062232Y-180055D01*
X1061358Y-181805D01*
X1060922Y-184139D01*
X1061358Y-186472D01*
X1062232Y-188222D01*
X1063542Y-189389D01*
X1065070Y-189972D01*
X1066598Y-189680D01*
X1067909Y-188806D01*
X1068782Y-187639D01*
G01X1082352Y-172472D02*
Y-189972D01*
G01X1079295Y-178306D02*
X1085409D01*
G01X1096577Y-182097D02*
X1103564D01*
X1102909Y-180055D01*
X1101817Y-178889D01*
X1100289Y-178306D01*
X1098760Y-178597D01*
X1097450Y-179472D01*
X1096577Y-181514D01*
X1096140Y-183264D01*
Y-185014D01*
X1096577Y-186764D01*
X1097669Y-188514D01*
X1098979Y-189680D01*
X1100507Y-189972D01*
X1102035Y-189389D01*
X1103564Y-187639D01*
G54D69*
X518967Y175596D03*
X520936D03*
X522904D03*
X524873D03*
Y187808D03*
X522904D03*
X520936D03*
X518967D03*
G54D79*
G01X45491Y94804D02*
X45445Y94850D01*
Y98346D01*
X43191Y100600D01*
X42400D01*
X39711Y97911D01*
G01X48374Y97687D02*
X44500Y101561D01*
Y102700D01*
X47489Y105689D01*
G01X92400Y84082D02*
X85918D01*
X80498Y89502D01*
X54789D01*
X53322Y90969D01*
Y92305D01*
G01D02*
X51800D01*
X50848Y93257D01*
Y95213D01*
G01X92400Y84082D02*
X95003D01*
X98569Y87648D01*
Y89811D01*
G01X92400Y85300D02*
Y84082D01*
G01X89100Y82782D02*
X85379D01*
X79961Y88200D01*
X53978D01*
X53189Y88989D01*
X52480Y89700D01*
X50979D01*
X50848Y89831D01*
G01D02*
Y91252D01*
X49770Y92330D01*
X47965D01*
G01X89100Y82782D02*
X95542D01*
X99418Y86658D01*
X101722D01*
G01X89100Y81000D02*
Y82782D01*
G01X46252Y151834D02*
Y153348D01*
X42300Y157300D01*
X41222D01*
X38232Y154310D01*
G01X49096Y154744D02*
X47656D01*
X43600Y158800D01*
Y159678D01*
X46010Y162088D01*
G01X53974Y149270D02*
X53130D01*
X51570Y150830D01*
Y152270D01*
G01X53974Y149270D02*
Y147026D01*
X56200Y144800D01*
G01D02*
X57608Y143392D01*
Y138092D01*
X62002Y133698D01*
X71458D01*
X73073Y135313D01*
Y137334D01*
G01X57400Y146000D02*
X56200Y144800D01*
G01X51500Y146796D02*
Y148500D01*
X50640Y149360D01*
X48726D01*
G01X54600Y140600D02*
X56308D01*
G01D02*
Y142792D01*
X52304Y146796D01*
X51500D01*
G01X56308Y140600D02*
Y137553D01*
X61463Y132398D01*
X71997D01*
X73435Y133836D01*
X73612D01*
X73957Y134181D01*
X76226D01*
G01X509994Y212056D02*
X512744D01*
X514100Y210700D01*
Y206968D01*
X512680Y205548D01*
G01X516810Y202048D02*
X515700Y200938D01*
Y199282D01*
X516632Y198350D01*
G01D02*
X515400Y197118D01*
Y194600D01*
G01D02*
Y188639D01*
X516231Y187808D01*
X518967D01*
G01X517100Y194600D02*
X515400D01*
G01X512680Y202048D02*
X514200Y200528D01*
Y199418D01*
X513132Y198350D01*
G01D02*
X514100Y197382D01*
Y188100D01*
X515814Y186386D01*
Y184655D01*
G01X509300Y198400D02*
X509350Y198350D01*
X513132D01*
G01X520994Y212056D02*
X516656D01*
X515700Y211100D01*
Y206658D01*
X516810Y205548D01*
M02*
